FILE_TYPE = MACRO_DRAWING;
SET COLOR_WIRE YELLOW;
SET COLOR_PROP ORANGE;
SET COLOR_DOT WHITE;
SET COLOR_ARC YELLOW;
SET COLOR_BODY GREEN;
SET COLOR_NOTE PURPLE;
SET PROP_DISPLAY VALUE;
SET PAGE_NUMBER P79;
FORCEADD Q_CAP..1
(-4425 -2375);
FORCEPROP 1 LAST PART_NUMBER CH647KMEA04
J 0
(-4375 -2525);
DISPLAY 0.638298 (-4375 -2525);
DISPLAY INVISIBLE (-4375 -2525);
FORCEPROP 1 LAST VOLTAGE 4V
J 0
(-4375 -2375);
DISPLAY 0.638298 (-4375 -2375);
FORCEPROP 1 LAST TOLERANCE 20%
J 0
(-4375 -2425);
DISPLAY 0.638298 (-4375 -2425);
FORCEPROP 1 LAST PACK_TYPE C0805
J 0
(-4375 -2575);
DISPLAY 0.638298 (-4375 -2575);
FORCEPROP 1 LAST MATERIAL X6S
J 0
(-4375 -2475);
DISPLAY 0.638298 (-4375 -2475);
FORCEPROP 1 LAST VALUE 47UF
J 0
(-4375 -2325);
DISPLAY 0.638298 (-4375 -2325);
FORCEPROP 1 LAST $LOCATION C450
J 0
(-4375 -2275);
DISPLAY 0.978723 (-4375 -2275);
FORCEPROP 1 LASTPIN (-4425 -2275) $PN 1
J 0
(-4415 -2295);
DISPLAY 0.787234 (-4415 -2295);
FORCEPROP 1 LASTPIN (-4425 -2475) $PN 2
J 0
(-4415 -2495);
DISPLAY 0.787234 (-4415 -2495);
FORCEPROP 2 LAST CDS_LIB pure_quanta
J 0
(-4425 -2375);
PAINT MONO (-4425 -2375);
DISPLAY INVISIBLE (-4425 -2375);
FORCEPROP 2 LAST CDS_LOCATION C450
J 0
(-4375 -2175);
DISPLAY 1.021277 (-4375 -2175);
DISPLAY INVISIBLE (-4375 -2175);
FORCEPROP 2 LAST $SEC 1
J 0
(-4375 -2175);
DISPLAY 0.680851 (-4375 -2175);
PAINT MONO (-4375 -2175);
DISPLAY INVISIBLE (-4375 -2175);
FORCEPROP 2 LAST CDS_SEC 1
J 0
(-4375 -2175);
DISPLAY 1.021277 (-4375 -2175);
DISPLAY INVISIBLE (-4375 -2175);
FORCEPROP 1 LAST PATH I1
J 0
(-4375 -2225);
DISPLAY 0.978723 (-4375 -2225);
PAINT WHITE (-4375 -2225);
DISPLAY INVISIBLE (-4375 -2225);
FORCEADD Q_CAP..1
(-3075 -1400);
FORCEPROP 1 LAST PART_NUMBER CH647KMEA04
J 0
(-3025 -1550);
DISPLAY 0.638298 (-3025 -1550);
DISPLAY INVISIBLE (-3025 -1550);
FORCEPROP 1 LAST VOLTAGE 4V
J 0
(-3025 -1400);
DISPLAY 0.638298 (-3025 -1400);
FORCEPROP 1 LAST TOLERANCE 20%
J 0
(-3025 -1450);
DISPLAY 0.638298 (-3025 -1450);
FORCEPROP 1 LAST PACK_TYPE C0805
J 0
(-3025 -1600);
DISPLAY 0.638298 (-3025 -1600);
FORCEPROP 1 LAST MATERIAL X6S
J 0
(-3025 -1500);
DISPLAY 0.638298 (-3025 -1500);
FORCEPROP 1 LAST VALUE 47UF
J 0
(-3025 -1350);
DISPLAY 0.638298 (-3025 -1350);
FORCEPROP 1 LAST $LOCATION C487
J 0
(-3025 -1300);
DISPLAY 0.978723 (-3025 -1300);
FORCEPROP 1 LASTPIN (-3075 -1300) $PN 1
J 0
(-3065 -1320);
DISPLAY 0.787234 (-3065 -1320);
FORCEPROP 1 LASTPIN (-3075 -1500) $PN 2
J 0
(-3065 -1520);
DISPLAY 0.787234 (-3065 -1520);
FORCEPROP 2 LAST CDS_LIB pure_quanta
J 0
(-3075 -1400);
PAINT MONO (-3075 -1400);
DISPLAY INVISIBLE (-3075 -1400);
FORCEPROP 2 LAST CDS_LOCATION C487
J 0
(-3025 -1200);
DISPLAY 1.021277 (-3025 -1200);
DISPLAY INVISIBLE (-3025 -1200);
FORCEPROP 2 LAST $SEC 1
J 0
(-3025 -1200);
DISPLAY 0.680851 (-3025 -1200);
PAINT MONO (-3025 -1200);
DISPLAY INVISIBLE (-3025 -1200);
FORCEPROP 2 LAST CDS_SEC 1
J 0
(-3025 -1200);
DISPLAY 1.021277 (-3025 -1200);
DISPLAY INVISIBLE (-3025 -1200);
FORCEPROP 1 LAST PATH I10
J 0
(-3025 -1250);
DISPLAY 0.978723 (-3025 -1250);
PAINT WHITE (-3025 -1250);
DISPLAY INVISIBLE (-3025 -1250);
FORCEADD Q_CAP..1
(-3525 -1400);
FORCEPROP 1 LAST PART_NUMBER CH647KMEA04
J 0
(-3475 -1550);
DISPLAY 0.638298 (-3475 -1550);
DISPLAY INVISIBLE (-3475 -1550);
FORCEPROP 1 LAST VOLTAGE 4V
J 0
(-3475 -1400);
DISPLAY 0.638298 (-3475 -1400);
FORCEPROP 1 LAST TOLERANCE 20%
J 0
(-3475 -1450);
DISPLAY 0.638298 (-3475 -1450);
FORCEPROP 1 LAST PACK_TYPE C0805
J 0
(-3475 -1600);
DISPLAY 0.638298 (-3475 -1600);
FORCEPROP 1 LAST VALUE 47UF
J 0
(-3475 -1350);
DISPLAY 0.638298 (-3475 -1350);
FORCEPROP 1 LAST MATERIAL X6S
J 0
(-3475 -1500);
DISPLAY 0.638298 (-3475 -1500);
FORCEPROP 1 LAST $LOCATION C486
J 0
(-3475 -1300);
DISPLAY 0.978723 (-3475 -1300);
FORCEPROP 1 LASTPIN (-3525 -1300) $PN 1
J 0
(-3515 -1320);
DISPLAY 0.787234 (-3515 -1320);
FORCEPROP 1 LASTPIN (-3525 -1500) $PN 2
J 0
(-3515 -1520);
DISPLAY 0.787234 (-3515 -1520);
FORCEPROP 2 LAST CDS_LIB pure_quanta
J 0
(-3525 -1400);
PAINT MONO (-3525 -1400);
DISPLAY INVISIBLE (-3525 -1400);
FORCEPROP 2 LAST CDS_LOCATION C486
J 0
(-3475 -1200);
DISPLAY 1.021277 (-3475 -1200);
DISPLAY INVISIBLE (-3475 -1200);
FORCEPROP 2 LAST $SEC 1
J 0
(-3475 -1200);
DISPLAY 0.680851 (-3475 -1200);
PAINT MONO (-3475 -1200);
DISPLAY INVISIBLE (-3475 -1200);
FORCEPROP 2 LAST CDS_SEC 1
J 0
(-3475 -1200);
DISPLAY 1.021277 (-3475 -1200);
DISPLAY INVISIBLE (-3475 -1200);
FORCEPROP 1 LAST PATH I11
J 0
(-3475 -1250);
DISPLAY 0.978723 (-3475 -1250);
PAINT WHITE (-3475 -1250);
DISPLAY INVISIBLE (-3475 -1250);
FORCEADD Q_CAP..1
(-3975 -1400);
FORCEPROP 1 LAST PART_NUMBER CH647KMEA04
J 0
(-3925 -1550);
DISPLAY 0.638298 (-3925 -1550);
DISPLAY INVISIBLE (-3925 -1550);
FORCEPROP 1 LAST TOLERANCE 20%
J 0
(-3925 -1450);
DISPLAY 0.638298 (-3925 -1450);
FORCEPROP 1 LAST VOLTAGE 4V
J 0
(-3925 -1400);
DISPLAY 0.638298 (-3925 -1400);
FORCEPROP 1 LAST PACK_TYPE C0805
J 0
(-3925 -1600);
DISPLAY 0.638298 (-3925 -1600);
FORCEPROP 1 LAST MATERIAL X6S
J 0
(-3925 -1500);
DISPLAY 0.638298 (-3925 -1500);
FORCEPROP 1 LAST VALUE 47UF
J 0
(-3925 -1350);
DISPLAY 0.638298 (-3925 -1350);
FORCEPROP 1 LAST $LOCATION C484
J 0
(-3925 -1300);
DISPLAY 0.978723 (-3925 -1300);
FORCEPROP 1 LASTPIN (-3975 -1300) $PN 1
J 0
(-3965 -1320);
DISPLAY 0.787234 (-3965 -1320);
FORCEPROP 1 LASTPIN (-3975 -1500) $PN 2
J 0
(-3965 -1520);
DISPLAY 0.787234 (-3965 -1520);
FORCEPROP 2 LAST CDS_LIB pure_quanta
J 0
(-3975 -1400);
PAINT MONO (-3975 -1400);
DISPLAY INVISIBLE (-3975 -1400);
FORCEPROP 2 LAST CDS_LOCATION C484
J 0
(-3925 -1200);
DISPLAY 1.021277 (-3925 -1200);
DISPLAY INVISIBLE (-3925 -1200);
FORCEPROP 2 LAST $SEC 1
J 0
(-3925 -1200);
DISPLAY 0.680851 (-3925 -1200);
PAINT MONO (-3925 -1200);
DISPLAY INVISIBLE (-3925 -1200);
FORCEPROP 2 LAST CDS_SEC 1
J 0
(-3925 -1200);
DISPLAY 1.021277 (-3925 -1200);
DISPLAY INVISIBLE (-3925 -1200);
FORCEPROP 1 LAST PATH I12
J 0
(-3925 -1250);
DISPLAY 0.978723 (-3925 -1250);
PAINT WHITE (-3925 -1250);
DISPLAY INVISIBLE (-3925 -1250);
FORCEADD Q_CAP..1
(-4425 -1400);
FORCEPROP 1 LAST PART_NUMBER CH647KMEA04
J 0
(-4375 -1550);
DISPLAY 0.638298 (-4375 -1550);
DISPLAY INVISIBLE (-4375 -1550);
FORCEPROP 1 LAST VOLTAGE 4V
J 0
(-4375 -1400);
DISPLAY 0.638298 (-4375 -1400);
FORCEPROP 1 LAST TOLERANCE 20%
J 0
(-4375 -1450);
DISPLAY 0.638298 (-4375 -1450);
FORCEPROP 1 LAST PACK_TYPE C0805
J 0
(-4375 -1600);
DISPLAY 0.638298 (-4375 -1600);
FORCEPROP 1 LAST MATERIAL X6S
J 0
(-4375 -1500);
DISPLAY 0.638298 (-4375 -1500);
FORCEPROP 1 LAST VALUE 47UF
J 0
(-4375 -1350);
DISPLAY 0.638298 (-4375 -1350);
FORCEPROP 1 LAST $LOCATION C481
J 0
(-4375 -1300);
DISPLAY 0.978723 (-4375 -1300);
FORCEPROP 1 LASTPIN (-4425 -1300) $PN 1
J 0
(-4415 -1320);
DISPLAY 0.787234 (-4415 -1320);
FORCEPROP 1 LASTPIN (-4425 -1500) $PN 2
J 0
(-4415 -1520);
DISPLAY 0.787234 (-4415 -1520);
FORCEPROP 2 LAST CDS_LIB pure_quanta
J 0
(-4425 -1400);
PAINT MONO (-4425 -1400);
DISPLAY INVISIBLE (-4425 -1400);
FORCEPROP 2 LAST CDS_LOCATION C481
J 0
(-4375 -1200);
DISPLAY 1.021277 (-4375 -1200);
DISPLAY INVISIBLE (-4375 -1200);
FORCEPROP 2 LAST $SEC 1
J 0
(-4375 -1200);
DISPLAY 0.680851 (-4375 -1200);
PAINT MONO (-4375 -1200);
DISPLAY INVISIBLE (-4375 -1200);
FORCEPROP 2 LAST CDS_SEC 1
J 0
(-4375 -1200);
DISPLAY 1.021277 (-4375 -1200);
DISPLAY INVISIBLE (-4375 -1200);
FORCEPROP 1 LAST PATH I13
J 0
(-4375 -1250);
DISPLAY 0.978723 (-4375 -1250);
PAINT WHITE (-4375 -1250);
DISPLAY INVISIBLE (-4375 -1250);
FORCEADD UNIVERSAL_POWER..1
(-4425 -1125);
FORCEPROP 3 LASTPIN (-4425 -1175) SIG_NAME PVCCINFAON_CPU1\g
J 0
(-4415 -1165);
DISPLAY 0.659574 (-4415 -1165);
PAINT MONO (-4415 -1165);
DISPLAY INVISIBLE (-4415 -1165);
FORCEPROP 1 LAST HDL_POWER PVCCINFAON_CPU1
J 1
(-4150 -1075);
DISPLAY 0.872340 (-4150 -1075);
PAINT GREEN (-4150 -1075);
FORCEPROP 2 LAST CDS_LIB logical_power
J 0
(-4425 -1125);
PAINT MONO (-4425 -1125);
DISPLAY INVISIBLE (-4425 -1125);
FORCEPROP 1 LAST PATH I14
J 0
(-4375 -1100);
DISPLAY 0.872340 (-4375 -1100);
PAINT AQUA (-4375 -1100);
DISPLAY INVISIBLE (-4375 -1100);
FORCEADD Q_CAP..1
(-4425 -400);
FORCEPROP 1 LAST PART_NUMBER CH647KMEA04
J 0
(-4375 -550);
DISPLAY 0.638298 (-4375 -550);
DISPLAY INVISIBLE (-4375 -550);
FORCEPROP 1 LAST TOLERANCE 20%
J 0
(-4375 -450);
DISPLAY 0.638298 (-4375 -450);
FORCEPROP 1 LAST VOLTAGE 4V
J 0
(-4375 -400);
DISPLAY 0.638298 (-4375 -400);
FORCEPROP 1 LAST PACK_TYPE C0805
J 0
(-4375 -600);
DISPLAY 0.638298 (-4375 -600);
FORCEPROP 1 LAST MATERIAL X6S
J 0
(-4375 -500);
DISPLAY 0.638298 (-4375 -500);
FORCEPROP 1 LAST VALUE 47UF
J 0
(-4375 -350);
DISPLAY 0.638298 (-4375 -350);
FORCEPROP 1 LAST $LOCATION C456
J 0
(-4375 -300);
DISPLAY 0.978723 (-4375 -300);
FORCEPROP 1 LASTPIN (-4425 -300) $PN 1
J 0
(-4415 -320);
DISPLAY 0.787234 (-4415 -320);
FORCEPROP 1 LASTPIN (-4425 -500) $PN 2
J 0
(-4415 -520);
DISPLAY 0.787234 (-4415 -520);
FORCEPROP 2 LAST CDS_LIB pure_quanta
J 0
(-4425 -400);
PAINT MONO (-4425 -400);
DISPLAY INVISIBLE (-4425 -400);
FORCEPROP 2 LAST CDS_LOCATION C456
J 0
(-4375 -200);
DISPLAY 1.021277 (-4375 -200);
DISPLAY INVISIBLE (-4375 -200);
FORCEPROP 2 LAST $SEC 1
J 0
(-4375 -200);
DISPLAY 0.680851 (-4375 -200);
PAINT MONO (-4375 -200);
DISPLAY INVISIBLE (-4375 -200);
FORCEPROP 2 LAST CDS_SEC 1
J 0
(-4375 -200);
DISPLAY 1.021277 (-4375 -200);
DISPLAY INVISIBLE (-4375 -200);
FORCEPROP 1 LAST PATH I15
J 0
(-4375 -250);
DISPLAY 0.978723 (-4375 -250);
PAINT WHITE (-4375 -250);
DISPLAY INVISIBLE (-4375 -250);
FORCEADD Q_CAP..1
(-3975 -400);
FORCEPROP 1 LAST PART_NUMBER CH647KMEA04
J 0
(-3925 -550);
DISPLAY 0.638298 (-3925 -550);
DISPLAY INVISIBLE (-3925 -550);
FORCEPROP 1 LAST VOLTAGE 4V
J 0
(-3925 -400);
DISPLAY 0.638298 (-3925 -400);
FORCEPROP 1 LAST TOLERANCE 20%
J 0
(-3925 -450);
DISPLAY 0.638298 (-3925 -450);
FORCEPROP 1 LAST PACK_TYPE C0805
J 0
(-3925 -600);
DISPLAY 0.638298 (-3925 -600);
FORCEPROP 1 LAST VALUE 47UF
J 0
(-3925 -350);
DISPLAY 0.638298 (-3925 -350);
FORCEPROP 1 LAST MATERIAL X6S
J 0
(-3925 -500);
DISPLAY 0.638298 (-3925 -500);
FORCEPROP 1 LAST $LOCATION C460
J 0
(-3925 -300);
DISPLAY 0.978723 (-3925 -300);
FORCEPROP 1 LASTPIN (-3975 -300) $PN 1
J 0
(-3965 -320);
DISPLAY 0.787234 (-3965 -320);
FORCEPROP 1 LASTPIN (-3975 -500) $PN 2
J 0
(-3965 -520);
DISPLAY 0.787234 (-3965 -520);
FORCEPROP 2 LAST CDS_LIB pure_quanta
J 0
(-3975 -400);
PAINT MONO (-3975 -400);
DISPLAY INVISIBLE (-3975 -400);
FORCEPROP 2 LAST CDS_LOCATION C460
J 0
(-3925 -200);
DISPLAY 1.021277 (-3925 -200);
DISPLAY INVISIBLE (-3925 -200);
FORCEPROP 2 LAST $SEC 1
J 0
(-3925 -200);
DISPLAY 0.680851 (-3925 -200);
PAINT MONO (-3925 -200);
DISPLAY INVISIBLE (-3925 -200);
FORCEPROP 2 LAST CDS_SEC 1
J 0
(-3925 -200);
DISPLAY 1.021277 (-3925 -200);
DISPLAY INVISIBLE (-3925 -200);
FORCEPROP 1 LAST PATH I16
J 0
(-3925 -250);
DISPLAY 0.978723 (-3925 -250);
PAINT WHITE (-3925 -250);
DISPLAY INVISIBLE (-3925 -250);
FORCEADD Q_CAP..1
(-3525 -400);
FORCEPROP 1 LAST PART_NUMBER CH647KMEA04
J 0
(-3475 -550);
DISPLAY 0.638298 (-3475 -550);
DISPLAY INVISIBLE (-3475 -550);
FORCEPROP 1 LAST VOLTAGE 4V
J 0
(-3475 -400);
DISPLAY 0.638298 (-3475 -400);
FORCEPROP 1 LAST TOLERANCE 20%
J 0
(-3475 -450);
DISPLAY 0.638298 (-3475 -450);
FORCEPROP 1 LAST PACK_TYPE C0805
J 0
(-3475 -600);
DISPLAY 0.638298 (-3475 -600);
FORCEPROP 1 LAST MATERIAL X6S
J 0
(-3475 -500);
DISPLAY 0.638298 (-3475 -500);
FORCEPROP 1 LAST VALUE 47UF
J 0
(-3475 -350);
DISPLAY 0.638298 (-3475 -350);
FORCEPROP 1 LAST $LOCATION C464
J 0
(-3475 -300);
DISPLAY 0.978723 (-3475 -300);
FORCEPROP 1 LASTPIN (-3525 -300) $PN 1
J 0
(-3515 -320);
DISPLAY 0.787234 (-3515 -320);
FORCEPROP 1 LASTPIN (-3525 -500) $PN 2
J 0
(-3515 -520);
DISPLAY 0.787234 (-3515 -520);
FORCEPROP 2 LAST CDS_LIB pure_quanta
J 0
(-3525 -400);
PAINT MONO (-3525 -400);
DISPLAY INVISIBLE (-3525 -400);
FORCEPROP 2 LAST CDS_LOCATION C464
J 0
(-3475 -200);
DISPLAY 1.021277 (-3475 -200);
DISPLAY INVISIBLE (-3475 -200);
FORCEPROP 2 LAST $SEC 1
J 0
(-3475 -200);
DISPLAY 0.680851 (-3475 -200);
PAINT MONO (-3475 -200);
DISPLAY INVISIBLE (-3475 -200);
FORCEPROP 2 LAST CDS_SEC 1
J 0
(-3475 -200);
DISPLAY 1.021277 (-3475 -200);
DISPLAY INVISIBLE (-3475 -200);
FORCEPROP 1 LAST PATH I17
J 0
(-3475 -250);
DISPLAY 0.978723 (-3475 -250);
PAINT WHITE (-3475 -250);
DISPLAY INVISIBLE (-3475 -250);
FORCEADD UNIVERSAL_POWER..1
(-4425 -125);
FORCEPROP 3 LASTPIN (-4425 -175) SIG_NAME PVCCFA_EHV_CPU1\g
J 0
(-4415 -165);
DISPLAY 0.659574 (-4415 -165);
PAINT MONO (-4415 -165);
DISPLAY INVISIBLE (-4415 -165);
FORCEPROP 1 LAST HDL_POWER PVCCFA_EHV_CPU1
J 1
(-4150 -75);
DISPLAY 0.872340 (-4150 -75);
PAINT GREEN (-4150 -75);
FORCEPROP 2 LAST CDS_LIB logical_power
J 0
(-4425 -125);
PAINT MONO (-4425 -125);
DISPLAY INVISIBLE (-4425 -125);
FORCEPROP 1 LAST PATH I18
J 0
(-4375 -100);
DISPLAY 0.872340 (-4375 -100);
PAINT AQUA (-4375 -100);
DISPLAY INVISIBLE (-4375 -100);
FORCEADD Q_CAP..1
(-4400 1475);
FORCEPROP 1 LAST PART_NUMBER CH647KMEA04
J 0
(-4350 1325);
DISPLAY 0.638298 (-4350 1325);
DISPLAY INVISIBLE (-4350 1325);
FORCEPROP 1 LAST VOLTAGE 4V
J 0
(-4350 1475);
DISPLAY 0.638298 (-4350 1475);
FORCEPROP 1 LAST TOLERANCE 20%
J 0
(-4350 1425);
DISPLAY 0.638298 (-4350 1425);
FORCEPROP 1 LAST PACK_TYPE C0805
J 0
(-4350 1275);
DISPLAY 0.638298 (-4350 1275);
FORCEPROP 1 LAST MATERIAL X6S
J 0
(-4350 1375);
DISPLAY 0.638298 (-4350 1375);
FORCEPROP 1 LAST VALUE 47UF
J 0
(-4350 1525);
DISPLAY 0.638298 (-4350 1525);
FORCEPROP 1 LAST $LOCATION C455
J 0
(-4350 1575);
DISPLAY 0.978723 (-4350 1575);
FORCEPROP 1 LASTPIN (-4400 1575) $PN 1
J 0
(-4390 1555);
DISPLAY 0.787234 (-4390 1555);
FORCEPROP 1 LASTPIN (-4400 1375) $PN 2
J 0
(-4390 1355);
DISPLAY 0.787234 (-4390 1355);
FORCEPROP 2 LAST CDS_LIB pure_quanta
J 0
(-4400 1475);
PAINT MONO (-4400 1475);
DISPLAY INVISIBLE (-4400 1475);
FORCEPROP 2 LAST CDS_LOCATION C455
J 0
(-4350 1675);
DISPLAY 1.021277 (-4350 1675);
DISPLAY INVISIBLE (-4350 1675);
FORCEPROP 2 LAST $SEC 1
J 0
(-4350 1675);
DISPLAY 0.680851 (-4350 1675);
PAINT MONO (-4350 1675);
DISPLAY INVISIBLE (-4350 1675);
FORCEPROP 2 LAST CDS_SEC 1
J 0
(-4350 1675);
DISPLAY 1.021277 (-4350 1675);
DISPLAY INVISIBLE (-4350 1675);
FORCEPROP 1 LAST PATH I19
J 0
(-4350 1625);
DISPLAY 0.978723 (-4350 1625);
PAINT WHITE (-4350 1625);
DISPLAY INVISIBLE (-4350 1625);
FORCEADD UNIVERSAL_POWER..1
(-4425 -2100);
FORCEPROP 3 LASTPIN (-4425 -2150) SIG_NAME PVCCFA_EHV_FIVRA_CPU1\g
J 0
(-4415 -2140);
DISPLAY 0.659574 (-4415 -2140);
PAINT MONO (-4415 -2140);
DISPLAY INVISIBLE (-4415 -2140);
FORCEPROP 1 LAST HDL_POWER PVCCFA_EHV_FIVRA_CPU1
J 1
(-4025 -2050);
DISPLAY 0.872340 (-4025 -2050);
PAINT GREEN (-4025 -2050);
FORCEPROP 2 LAST CDS_LIB logical_power
J 0
(-4425 -2100);
DISPLAY INVISIBLE (-4425 -2100);
FORCEPROP 1 LAST PATH I2
J 0
(-4375 -2075);
DISPLAY 0.872340 (-4375 -2075);
PAINT AQUA (-4375 -2075);
DISPLAY INVISIBLE (-4375 -2075);
FORCEADD Q_CAP..1
(-3950 1475);
FORCEPROP 1 LAST PART_NUMBER CH647KMEA04
J 0
(-3900 1325);
DISPLAY 0.638298 (-3900 1325);
DISPLAY INVISIBLE (-3900 1325);
FORCEPROP 1 LAST VOLTAGE 4V
J 0
(-3900 1475);
DISPLAY 0.638298 (-3900 1475);
FORCEPROP 1 LAST TOLERANCE 20%
J 0
(-3900 1425);
DISPLAY 0.638298 (-3900 1425);
FORCEPROP 1 LAST PACK_TYPE C0805
J 0
(-3900 1275);
DISPLAY 0.638298 (-3900 1275);
FORCEPROP 1 LAST MATERIAL X6S
J 0
(-3900 1375);
DISPLAY 0.638298 (-3900 1375);
FORCEPROP 1 LAST VALUE 47UF
J 0
(-3900 1525);
DISPLAY 0.638298 (-3900 1525);
FORCEPROP 1 LAST $LOCATION C459
J 0
(-3900 1575);
DISPLAY 0.978723 (-3900 1575);
FORCEPROP 1 LASTPIN (-3950 1575) $PN 1
J 0
(-3940 1555);
DISPLAY 0.787234 (-3940 1555);
FORCEPROP 1 LASTPIN (-3950 1375) $PN 2
J 0
(-3940 1355);
DISPLAY 0.787234 (-3940 1355);
FORCEPROP 2 LAST CDS_LIB pure_quanta
J 0
(-3950 1475);
PAINT MONO (-3950 1475);
DISPLAY INVISIBLE (-3950 1475);
FORCEPROP 2 LAST CDS_LOCATION C459
J 0
(-3900 1675);
DISPLAY 1.021277 (-3900 1675);
DISPLAY INVISIBLE (-3900 1675);
FORCEPROP 2 LAST $SEC 1
J 0
(-3900 1675);
DISPLAY 0.680851 (-3900 1675);
PAINT MONO (-3900 1675);
DISPLAY INVISIBLE (-3900 1675);
FORCEPROP 2 LAST CDS_SEC 1
J 0
(-3900 1675);
DISPLAY 1.021277 (-3900 1675);
DISPLAY INVISIBLE (-3900 1675);
FORCEPROP 1 LAST PATH I20
J 0
(-3900 1625);
DISPLAY 0.978723 (-3900 1625);
PAINT WHITE (-3900 1625);
DISPLAY INVISIBLE (-3900 1625);
FORCEADD Q_CAP..1
(-3500 1475);
FORCEPROP 1 LAST PART_NUMBER CH647KMEA04
J 0
(-3450 1325);
DISPLAY 0.638298 (-3450 1325);
DISPLAY INVISIBLE (-3450 1325);
FORCEPROP 1 LAST VOLTAGE 4V
J 0
(-3450 1475);
DISPLAY 0.638298 (-3450 1475);
FORCEPROP 1 LAST TOLERANCE 20%
J 0
(-3450 1425);
DISPLAY 0.638298 (-3450 1425);
FORCEPROP 1 LAST PACK_TYPE C0805
J 0
(-3450 1275);
DISPLAY 0.638298 (-3450 1275);
FORCEPROP 1 LAST MATERIAL X6S
J 0
(-3450 1375);
DISPLAY 0.638298 (-3450 1375);
FORCEPROP 1 LAST VALUE 47UF
J 0
(-3450 1525);
DISPLAY 0.638298 (-3450 1525);
FORCEPROP 1 LAST $LOCATION C463
J 0
(-3450 1575);
DISPLAY 0.978723 (-3450 1575);
FORCEPROP 1 LASTPIN (-3500 1575) $PN 1
J 0
(-3490 1555);
DISPLAY 0.787234 (-3490 1555);
FORCEPROP 1 LASTPIN (-3500 1375) $PN 2
J 0
(-3490 1355);
DISPLAY 0.787234 (-3490 1355);
FORCEPROP 2 LAST CDS_LIB pure_quanta
J 0
(-3500 1475);
PAINT MONO (-3500 1475);
DISPLAY INVISIBLE (-3500 1475);
FORCEPROP 2 LAST CDS_LOCATION C463
J 0
(-3450 1675);
DISPLAY 1.021277 (-3450 1675);
DISPLAY INVISIBLE (-3450 1675);
FORCEPROP 2 LAST $SEC 1
J 0
(-3450 1675);
DISPLAY 0.680851 (-3450 1675);
PAINT MONO (-3450 1675);
DISPLAY INVISIBLE (-3450 1675);
FORCEPROP 2 LAST CDS_SEC 1
J 0
(-3450 1675);
DISPLAY 1.021277 (-3450 1675);
DISPLAY INVISIBLE (-3450 1675);
FORCEPROP 1 LAST PATH I21
J 0
(-3450 1625);
DISPLAY 0.978723 (-3450 1625);
PAINT WHITE (-3450 1625);
DISPLAY INVISIBLE (-3450 1625);
FORCEADD UNIVERSAL_POWER..1
(-4400 1750);
FORCEPROP 3 LASTPIN (-4400 1700) SIG_NAME PVCCD_HV_CPU1\g
J 0
(-4390 1710);
DISPLAY 0.659574 (-4390 1710);
PAINT MONO (-4390 1710);
DISPLAY INVISIBLE (-4390 1710);
FORCEPROP 1 LAST HDL_POWER PVCCD_HV_CPU1
J 1
(-4175 1800);
DISPLAY 0.872340 (-4175 1800);
PAINT GREEN (-4175 1800);
FORCEPROP 2 LAST CDS_LIB logical_power
J 0
(-4400 1750);
PAINT MONO (-4400 1750);
DISPLAY INVISIBLE (-4400 1750);
FORCEPROP 1 LAST PATH I22
J 0
(-4350 1775);
DISPLAY 0.872340 (-4350 1775);
PAINT AQUA (-4350 1775);
DISPLAY INVISIBLE (-4350 1775);
FORCEADD Q_CAP..1
(-4400 2400);
FORCEPROP 1 LAST PART_NUMBER CH647KMEA04
J 0
(-4350 2250);
DISPLAY 0.638298 (-4350 2250);
DISPLAY INVISIBLE (-4350 2250);
FORCEPROP 1 LAST VOLTAGE 4V
J 0
(-4350 2400);
DISPLAY 0.638298 (-4350 2400);
FORCEPROP 1 LAST TOLERANCE 20%
J 0
(-4350 2350);
DISPLAY 0.638298 (-4350 2350);
FORCEPROP 1 LAST PACK_TYPE C0805
J 0
(-4350 2200);
DISPLAY 0.638298 (-4350 2200);
FORCEPROP 1 LAST MATERIAL X6S
J 0
(-4350 2300);
DISPLAY 0.638298 (-4350 2300);
FORCEPROP 1 LAST VALUE 47UF
J 0
(-4350 2450);
DISPLAY 0.638298 (-4350 2450);
FORCEPROP 1 LAST $LOCATION C342
J 0
(-4350 2500);
DISPLAY 0.638298 (-4350 2500);
FORCEPROP 1 LASTPIN (-4400 2500) $PN 1
J 0
(-4390 2480);
DISPLAY 0.787234 (-4390 2480);
FORCEPROP 1 LASTPIN (-4400 2300) $PN 2
J 0
(-4390 2280);
DISPLAY 0.787234 (-4390 2280);
FORCEPROP 2 LAST CDS_LIB pure_quanta
J 0
(-4400 2400);
PAINT MONO (-4400 2400);
DISPLAY INVISIBLE (-4400 2400);
FORCEPROP 1 LAST $LOCATION C342
J 0
(-4350 2600);
DISPLAY 1.021277 (-4350 2600);
DISPLAY INVISIBLE (-4350 2600);
FORCEPROP 2 LAST CDS_LOCATION C342
J 0
(-4350 2600);
DISPLAY 1.021277 (-4350 2600);
DISPLAY INVISIBLE (-4350 2600);
FORCEPROP 2 LAST $SEC 1
J 0
(-4350 2600);
DISPLAY 0.680851 (-4350 2600);
PAINT MONO (-4350 2600);
DISPLAY INVISIBLE (-4350 2600);
FORCEPROP 2 LAST CDS_SEC 1
J 0
(-4350 2600);
DISPLAY 1.021277 (-4350 2600);
DISPLAY INVISIBLE (-4350 2600);
FORCEPROP 1 LAST PATH I23
J 0
(-4350 2550);
DISPLAY 0.978723 (-4350 2550);
PAINT WHITE (-4350 2550);
DISPLAY INVISIBLE (-4350 2550);
FORCEADD Q_CAP..1
(-3950 2400);
FORCEPROP 1 LAST PART_NUMBER CH647KMEA04
J 0
(-3900 2250);
DISPLAY 0.638298 (-3900 2250);
DISPLAY INVISIBLE (-3900 2250);
FORCEPROP 1 LAST VOLTAGE 4V
J 0
(-3900 2400);
DISPLAY 0.638298 (-3900 2400);
FORCEPROP 1 LAST TOLERANCE 20%
J 0
(-3900 2350);
DISPLAY 0.638298 (-3900 2350);
FORCEPROP 1 LAST PACK_TYPE C0805
J 0
(-3900 2200);
DISPLAY 0.638298 (-3900 2200);
FORCEPROP 1 LAST MATERIAL X6S
J 0
(-3900 2300);
DISPLAY 0.638298 (-3900 2300);
FORCEPROP 1 LAST VALUE 47UF
J 0
(-3900 2450);
DISPLAY 0.638298 (-3900 2450);
FORCEPROP 1 LAST $LOCATION C344
J 0
(-3900 2500);
DISPLAY 0.638298 (-3900 2500);
FORCEPROP 1 LASTPIN (-3950 2500) $PN 1
J 0
(-3940 2480);
DISPLAY 0.787234 (-3940 2480);
FORCEPROP 1 LASTPIN (-3950 2300) $PN 2
J 0
(-3940 2280);
DISPLAY 0.787234 (-3940 2280);
FORCEPROP 2 LAST CDS_LIB pure_quanta
J 0
(-3950 2400);
PAINT MONO (-3950 2400);
DISPLAY INVISIBLE (-3950 2400);
FORCEPROP 1 LAST $LOCATION C344
J 0
(-3900 2600);
DISPLAY 1.021277 (-3900 2600);
DISPLAY INVISIBLE (-3900 2600);
FORCEPROP 2 LAST CDS_LOCATION C344
J 0
(-3900 2600);
DISPLAY 1.021277 (-3900 2600);
DISPLAY INVISIBLE (-3900 2600);
FORCEPROP 2 LAST $SEC 1
J 0
(-3900 2600);
DISPLAY 0.680851 (-3900 2600);
PAINT MONO (-3900 2600);
DISPLAY INVISIBLE (-3900 2600);
FORCEPROP 2 LAST CDS_SEC 1
J 0
(-3900 2600);
DISPLAY 1.021277 (-3900 2600);
DISPLAY INVISIBLE (-3900 2600);
FORCEPROP 1 LAST PATH I24
J 0
(-3900 2550);
DISPLAY 0.978723 (-3900 2550);
PAINT WHITE (-3900 2550);
DISPLAY INVISIBLE (-3900 2550);
FORCEADD Q_CAP..1
(-3500 2400);
FORCEPROP 1 LAST PART_NUMBER CH647KMEA04
J 0
(-3450 2250);
DISPLAY 0.638298 (-3450 2250);
DISPLAY INVISIBLE (-3450 2250);
FORCEPROP 1 LAST VOLTAGE 4V
J 0
(-3450 2400);
DISPLAY 0.638298 (-3450 2400);
FORCEPROP 1 LAST TOLERANCE 20%
J 0
(-3450 2350);
DISPLAY 0.638298 (-3450 2350);
FORCEPROP 1 LAST PACK_TYPE C0805
J 0
(-3450 2200);
DISPLAY 0.638298 (-3450 2200);
FORCEPROP 1 LAST MATERIAL X6S
J 0
(-3450 2300);
DISPLAY 0.638298 (-3450 2300);
FORCEPROP 1 LAST VALUE 47UF
J 0
(-3450 2450);
DISPLAY 0.638298 (-3450 2450);
FORCEPROP 1 LAST $LOCATION C346
J 0
(-3450 2500);
DISPLAY 0.638298 (-3450 2500);
FORCEPROP 1 LASTPIN (-3500 2500) $PN 1
J 0
(-3490 2480);
DISPLAY 0.787234 (-3490 2480);
FORCEPROP 1 LASTPIN (-3500 2300) $PN 2
J 0
(-3490 2280);
DISPLAY 0.787234 (-3490 2280);
FORCEPROP 2 LAST CDS_LIB pure_quanta
J 0
(-3500 2400);
PAINT MONO (-3500 2400);
DISPLAY INVISIBLE (-3500 2400);
FORCEPROP 1 LAST $LOCATION C346
J 0
(-3450 2600);
DISPLAY 1.021277 (-3450 2600);
DISPLAY INVISIBLE (-3450 2600);
FORCEPROP 2 LAST CDS_LOCATION C346
J 0
(-3450 2600);
DISPLAY 1.021277 (-3450 2600);
DISPLAY INVISIBLE (-3450 2600);
FORCEPROP 2 LAST $SEC 1
J 0
(-3450 2600);
DISPLAY 0.680851 (-3450 2600);
PAINT MONO (-3450 2600);
DISPLAY INVISIBLE (-3450 2600);
FORCEPROP 2 LAST CDS_SEC 1
J 0
(-3450 2600);
DISPLAY 1.021277 (-3450 2600);
DISPLAY INVISIBLE (-3450 2600);
FORCEPROP 1 LAST PATH I25
J 0
(-3450 2550);
DISPLAY 0.978723 (-3450 2550);
PAINT WHITE (-3450 2550);
DISPLAY INVISIBLE (-3450 2550);
FORCEADD Q_CAP..1
(-3075 -400);
FORCEPROP 1 LAST PART_NUMBER CH647KMEA04
J 0
(-3025 -550);
DISPLAY 0.638298 (-3025 -550);
DISPLAY INVISIBLE (-3025 -550);
FORCEPROP 1 LAST PACK_TYPE C0805
J 0
(-3025 -600);
DISPLAY 0.638298 (-3025 -600);
FORCEPROP 1 LAST VOLTAGE 4V
J 0
(-3025 -400);
DISPLAY 0.638298 (-3025 -400);
FORCEPROP 1 LAST MATERIAL X6S
J 0
(-3025 -500);
DISPLAY 0.638298 (-3025 -500);
FORCEPROP 1 LAST TOLERANCE 20%
J 0
(-3025 -450);
DISPLAY 0.638298 (-3025 -450);
FORCEPROP 1 LAST VALUE 47UF
J 0
(-3025 -350);
DISPLAY 0.638298 (-3025 -350);
FORCEPROP 1 LAST $LOCATION C468
J 0
(-3025 -300);
DISPLAY 0.978723 (-3025 -300);
FORCEPROP 1 LASTPIN (-3075 -300) $PN 1
J 0
(-3065 -320);
DISPLAY 0.787234 (-3065 -320);
FORCEPROP 1 LASTPIN (-3075 -500) $PN 2
J 0
(-3065 -520);
DISPLAY 0.787234 (-3065 -520);
FORCEPROP 2 LAST CDS_LIB pure_quanta
J 0
(-3075 -400);
PAINT MONO (-3075 -400);
DISPLAY INVISIBLE (-3075 -400);
FORCEPROP 2 LAST CDS_LOCATION C468
J 0
(-3025 -200);
DISPLAY 1.021277 (-3025 -200);
DISPLAY INVISIBLE (-3025 -200);
FORCEPROP 2 LAST $SEC 1
J 0
(-3025 -200);
DISPLAY 0.680851 (-3025 -200);
PAINT MONO (-3025 -200);
DISPLAY INVISIBLE (-3025 -200);
FORCEPROP 2 LAST CDS_SEC 1
J 0
(-3025 -200);
DISPLAY 1.021277 (-3025 -200);
DISPLAY INVISIBLE (-3025 -200);
FORCEPROP 1 LAST PATH I26
J 0
(-3025 -250);
DISPLAY 0.978723 (-3025 -250);
PAINT WHITE (-3025 -250);
DISPLAY INVISIBLE (-3025 -250);
FORCEADD Q_CAP..1
(-2625 -400);
FORCEPROP 1 LAST PART_NUMBER CH647LME900
J 0
(-2575 -550);
DISPLAY 0.638298 (-2575 -550);
DISPLAY INVISIBLE (-2575 -550);
FORCEPROP 1 LAST VALUE 47UF
J 0
(-2575 -350);
DISPLAY 0.638298 (-2575 -350);
FORCEPROP 1 LAST VOLTAGE 2.5V
J 0
(-2575 -400);
DISPLAY 0.638298 (-2575 -400);
FORCEPROP 1 LAST TOLERANCE 20%
J 0
(-2575 -450);
DISPLAY 0.638298 (-2575 -450);
FORCEPROP 1 LAST PACK_TYPE C0603
J 0
(-2575 -600);
DISPLAY 0.638298 (-2575 -600);
FORCEPROP 1 LAST MATERIAL X6S
J 0
(-2575 -500);
DISPLAY 0.638298 (-2575 -500);
FORCEPROP 1 LAST $LOCATION C472
J 0
(-2575 -300);
DISPLAY 0.978723 (-2575 -300);
FORCEPROP 1 LASTPIN (-2625 -300) $PN 1
J 0
(-2615 -320);
DISPLAY 0.787234 (-2615 -320);
FORCEPROP 1 LASTPIN (-2625 -500) $PN 2
J 0
(-2615 -520);
DISPLAY 0.787234 (-2615 -520);
FORCEPROP 2 LAST CDS_LIB pure_quanta
J 0
(-2625 -400);
PAINT MONO (-2625 -400);
DISPLAY INVISIBLE (-2625 -400);
FORCEPROP 2 LAST CDS_LOCATION C472
J 0
(-2575 -200);
DISPLAY 1.021277 (-2575 -200);
DISPLAY INVISIBLE (-2575 -200);
FORCEPROP 2 LAST $SEC 1
J 0
(-2575 -200);
DISPLAY 0.680851 (-2575 -200);
PAINT MONO (-2575 -200);
DISPLAY INVISIBLE (-2575 -200);
FORCEPROP 2 LAST CDS_SEC 1
J 0
(-2575 -200);
DISPLAY 1.021277 (-2575 -200);
DISPLAY INVISIBLE (-2575 -200);
FORCEPROP 1 LAST PATH I27
J 0
(-2575 -250);
DISPLAY 0.978723 (-2575 -250);
PAINT WHITE (-2575 -250);
DISPLAY INVISIBLE (-2575 -250);
FORCEADD UNIVERSAL_GND..1
(-2175 -750);
FORCEPROP 3 LASTPIN (-2175 -700) SIG_NAME GND\g
J 0
(-2165 -690);
DISPLAY 0.659574 (-2165 -690);
PAINT MONO (-2165 -690);
DISPLAY INVISIBLE (-2165 -690);
FORCEPROP 2 LAST CDS_LIB logical_power
J 0
(-2175 -750);
PAINT MONO (-2175 -750);
DISPLAY INVISIBLE (-2175 -750);
FORCEPROP 1 LAST HDL_POWER GND
J 1
(-2150 -825);
DISPLAY 0.872340 (-2150 -825);
PAINT GREEN (-2150 -825);
DISPLAY INVISIBLE (-2150 -825);
FORCEPROP 1 LAST PATH I28
J 0
(-2100 -750);
DISPLAY 0.872340 (-2100 -750);
PAINT AQUA (-2100 -750);
DISPLAY INVISIBLE (-2100 -750);
FORCEADD Q_CAP..1
(-2175 -400);
FORCEPROP 1 LAST PART_NUMBER CH647LME900
J 0
(-2125 -550);
DISPLAY 0.638298 (-2125 -550);
DISPLAY INVISIBLE (-2125 -550);
FORCEPROP 1 LAST VOLTAGE 2.5V
J 0
(-2125 -400);
DISPLAY 0.638298 (-2125 -400);
FORCEPROP 1 LAST VALUE 47UF
J 0
(-2125 -350);
DISPLAY 0.638298 (-2125 -350);
FORCEPROP 1 LAST TOLERANCE 20%
J 0
(-2125 -450);
DISPLAY 0.638298 (-2125 -450);
FORCEPROP 1 LAST PACK_TYPE C0603
J 0
(-2125 -600);
DISPLAY 0.638298 (-2125 -600);
FORCEPROP 1 LAST MATERIAL X6S
J 0
(-2125 -500);
DISPLAY 0.638298 (-2125 -500);
FORCEPROP 1 LAST $LOCATION C475
J 0
(-2125 -300);
DISPLAY 0.978723 (-2125 -300);
FORCEPROP 1 LASTPIN (-2175 -300) $PN 1
J 0
(-2165 -320);
DISPLAY 0.787234 (-2165 -320);
FORCEPROP 1 LASTPIN (-2175 -500) $PN 2
J 0
(-2165 -520);
DISPLAY 0.787234 (-2165 -520);
FORCEPROP 2 LAST CDS_LIB pure_quanta
J 0
(-2175 -400);
PAINT MONO (-2175 -400);
DISPLAY INVISIBLE (-2175 -400);
FORCEPROP 2 LAST CDS_LOCATION C475
J 0
(-2125 -200);
DISPLAY 1.021277 (-2125 -200);
DISPLAY INVISIBLE (-2125 -200);
FORCEPROP 2 LAST $SEC 1
J 0
(-2125 -200);
DISPLAY 0.680851 (-2125 -200);
PAINT MONO (-2125 -200);
DISPLAY INVISIBLE (-2125 -200);
FORCEPROP 2 LAST CDS_SEC 1
J 0
(-2125 -200);
DISPLAY 1.021277 (-2125 -200);
DISPLAY INVISIBLE (-2125 -200);
FORCEPROP 1 LAST PATH I29
J 0
(-2125 -250);
DISPLAY 0.978723 (-2125 -250);
PAINT WHITE (-2125 -250);
DISPLAY INVISIBLE (-2125 -250);
FORCEADD Q_CAP..1
(-3975 -2375);
FORCEPROP 1 LAST PART_NUMBER CH647KMEA04
J 0
(-3925 -2525);
DISPLAY 0.638298 (-3925 -2525);
DISPLAY INVISIBLE (-3925 -2525);
FORCEPROP 1 LAST VOLTAGE 4V
J 0
(-3925 -2375);
DISPLAY 0.638298 (-3925 -2375);
FORCEPROP 1 LAST TOLERANCE 20%
J 0
(-3925 -2425);
DISPLAY 0.638298 (-3925 -2425);
FORCEPROP 1 LAST PACK_TYPE C0805
J 0
(-3925 -2575);
DISPLAY 0.638298 (-3925 -2575);
FORCEPROP 1 LAST MATERIAL X6S
J 0
(-3925 -2475);
DISPLAY 0.638298 (-3925 -2475);
FORCEPROP 1 LAST VALUE 47UF
J 0
(-3925 -2325);
DISPLAY 0.638298 (-3925 -2325);
FORCEPROP 1 LAST $LOCATION C454
J 0
(-3925 -2275);
DISPLAY 0.978723 (-3925 -2275);
FORCEPROP 1 LASTPIN (-3975 -2275) $PN 1
J 0
(-3965 -2295);
DISPLAY 0.787234 (-3965 -2295);
FORCEPROP 1 LASTPIN (-3975 -2475) $PN 2
J 0
(-3965 -2495);
DISPLAY 0.787234 (-3965 -2495);
FORCEPROP 2 LAST CDS_LIB pure_quanta
J 0
(-3975 -2375);
PAINT MONO (-3975 -2375);
DISPLAY INVISIBLE (-3975 -2375);
FORCEPROP 2 LAST CDS_LOCATION C454
J 0
(-3925 -2175);
DISPLAY 1.021277 (-3925 -2175);
DISPLAY INVISIBLE (-3925 -2175);
FORCEPROP 2 LAST $SEC 1
J 0
(-3925 -2175);
DISPLAY 0.680851 (-3925 -2175);
PAINT MONO (-3925 -2175);
DISPLAY INVISIBLE (-3925 -2175);
FORCEPROP 2 LAST CDS_SEC 1
J 0
(-3925 -2175);
DISPLAY 1.021277 (-3925 -2175);
DISPLAY INVISIBLE (-3925 -2175);
FORCEPROP 1 LAST PATH I3
J 0
(-3925 -2225);
DISPLAY 0.978723 (-3925 -2225);
PAINT WHITE (-3925 -2225);
DISPLAY INVISIBLE (-3925 -2225);
FORCEADD UNIVERSAL_GND..1
(-3050 1150);
FORCEPROP 3 LASTPIN (-3050 1200) SIG_NAME GND\g
J 0
(-3040 1210);
DISPLAY 0.659574 (-3040 1210);
PAINT MONO (-3040 1210);
DISPLAY INVISIBLE (-3040 1210);
FORCEPROP 2 LAST CDS_LIB logical_power
J 0
(-3050 1150);
PAINT MONO (-3050 1150);
DISPLAY INVISIBLE (-3050 1150);
FORCEPROP 1 LAST HDL_POWER GND
J 1
(-3025 1075);
DISPLAY 0.872340 (-3025 1075);
PAINT GREEN (-3025 1075);
DISPLAY INVISIBLE (-3025 1075);
FORCEPROP 1 LAST PATH I30
J 0
(-2975 1150);
DISPLAY 0.872340 (-2975 1150);
PAINT AQUA (-2975 1150);
DISPLAY INVISIBLE (-2975 1150);
FORCEADD Q_CAP..1
(-3050 1475);
FORCEPROP 1 LAST PART_NUMBER CH647KMEA04
J 0
(-3000 1325);
DISPLAY 0.638298 (-3000 1325);
DISPLAY INVISIBLE (-3000 1325);
FORCEPROP 1 LAST VOLTAGE 4V
J 0
(-3000 1475);
DISPLAY 0.638298 (-3000 1475);
FORCEPROP 1 LAST TOLERANCE 20%
J 0
(-3000 1425);
DISPLAY 0.638298 (-3000 1425);
FORCEPROP 1 LAST PACK_TYPE C0805
J 0
(-3000 1275);
DISPLAY 0.638298 (-3000 1275);
FORCEPROP 1 LAST MATERIAL X6S
J 0
(-3000 1375);
DISPLAY 0.638298 (-3000 1375);
FORCEPROP 1 LAST VALUE 47UF
J 0
(-3000 1525);
DISPLAY 0.638298 (-3000 1525);
FORCEPROP 1 LAST $LOCATION C467
J 0
(-3000 1575);
DISPLAY 0.978723 (-3000 1575);
FORCEPROP 1 LASTPIN (-3050 1575) $PN 1
J 0
(-3040 1555);
DISPLAY 0.787234 (-3040 1555);
FORCEPROP 1 LASTPIN (-3050 1375) $PN 2
J 0
(-3040 1355);
DISPLAY 0.787234 (-3040 1355);
FORCEPROP 2 LAST CDS_LIB pure_quanta
J 0
(-3050 1475);
PAINT MONO (-3050 1475);
DISPLAY INVISIBLE (-3050 1475);
FORCEPROP 2 LAST CDS_LOCATION C467
J 0
(-3000 1675);
DISPLAY 1.021277 (-3000 1675);
DISPLAY INVISIBLE (-3000 1675);
FORCEPROP 2 LAST $SEC 1
J 0
(-3000 1675);
DISPLAY 0.680851 (-3000 1675);
PAINT MONO (-3000 1675);
DISPLAY INVISIBLE (-3000 1675);
FORCEPROP 2 LAST CDS_SEC 1
J 0
(-3000 1675);
DISPLAY 1.021277 (-3000 1675);
DISPLAY INVISIBLE (-3000 1675);
FORCEPROP 1 LAST PATH I31
J 0
(-3000 1625);
DISPLAY 0.978723 (-3000 1625);
PAINT WHITE (-3000 1625);
DISPLAY INVISIBLE (-3000 1625);
FORCEADD Q_CAP..1
(-3050 2400);
FORCEPROP 1 LAST PART_NUMBER CH647KMEA04
J 0
(-3000 2250);
DISPLAY 0.638298 (-3000 2250);
DISPLAY INVISIBLE (-3000 2250);
FORCEPROP 1 LAST VOLTAGE 4V
J 0
(-3000 2400);
DISPLAY 0.638298 (-3000 2400);
FORCEPROP 1 LAST TOLERANCE 20%
J 0
(-3000 2350);
DISPLAY 0.638298 (-3000 2350);
FORCEPROP 1 LAST PACK_TYPE C0805
J 0
(-3000 2200);
DISPLAY 0.638298 (-3000 2200);
FORCEPROP 1 LAST MATERIAL X6S
J 0
(-3000 2300);
DISPLAY 0.638298 (-3000 2300);
FORCEPROP 1 LAST VALUE 47UF
J 0
(-3000 2450);
DISPLAY 0.638298 (-3000 2450);
FORCEPROP 1 LAST $LOCATION C348
J 0
(-3000 2500);
DISPLAY 0.638298 (-3000 2500);
FORCEPROP 1 LASTPIN (-3050 2500) $PN 1
J 0
(-3040 2480);
DISPLAY 0.787234 (-3040 2480);
FORCEPROP 1 LASTPIN (-3050 2300) $PN 2
J 0
(-3040 2280);
DISPLAY 0.787234 (-3040 2280);
FORCEPROP 2 LAST CDS_LIB pure_quanta
J 0
(-3050 2400);
PAINT MONO (-3050 2400);
DISPLAY INVISIBLE (-3050 2400);
FORCEPROP 1 LAST $LOCATION C348
J 0
(-3000 2600);
DISPLAY 1.021277 (-3000 2600);
DISPLAY INVISIBLE (-3000 2600);
FORCEPROP 2 LAST CDS_LOCATION C348
J 0
(-3000 2600);
DISPLAY 1.021277 (-3000 2600);
DISPLAY INVISIBLE (-3000 2600);
FORCEPROP 2 LAST $SEC 1
J 0
(-3000 2600);
DISPLAY 0.680851 (-3000 2600);
PAINT MONO (-3000 2600);
DISPLAY INVISIBLE (-3000 2600);
FORCEPROP 2 LAST CDS_SEC 1
J 0
(-3000 2600);
DISPLAY 1.021277 (-3000 2600);
DISPLAY INVISIBLE (-3000 2600);
FORCEPROP 1 LAST PATH I32
J 0
(-3000 2550);
DISPLAY 0.978723 (-3000 2550);
PAINT WHITE (-3000 2550);
DISPLAY INVISIBLE (-3000 2550);
FORCEADD Q_CAP..1
(-2600 2400);
FORCEPROP 1 LAST PART_NUMBER CH647KMEA04
J 0
(-2550 2250);
DISPLAY 0.638298 (-2550 2250);
DISPLAY INVISIBLE (-2550 2250);
FORCEPROP 1 LAST VOLTAGE 4V
J 0
(-2550 2400);
DISPLAY 0.638298 (-2550 2400);
FORCEPROP 1 LAST TOLERANCE 20%
J 0
(-2550 2350);
DISPLAY 0.638298 (-2550 2350);
FORCEPROP 1 LAST PACK_TYPE C0805
J 0
(-2550 2200);
DISPLAY 0.638298 (-2550 2200);
FORCEPROP 1 LAST MATERIAL X6S
J 0
(-2550 2300);
DISPLAY 0.638298 (-2550 2300);
FORCEPROP 1 LAST VALUE 47UF
J 0
(-2550 2450);
DISPLAY 0.638298 (-2550 2450);
FORCEPROP 1 LAST $LOCATION C350
J 0
(-2550 2500);
DISPLAY 0.638298 (-2550 2500);
FORCEPROP 1 LASTPIN (-2600 2500) $PN 1
J 0
(-2590 2480);
DISPLAY 0.787234 (-2590 2480);
FORCEPROP 1 LASTPIN (-2600 2300) $PN 2
J 0
(-2590 2280);
DISPLAY 0.787234 (-2590 2280);
FORCEPROP 2 LAST CDS_LIB pure_quanta
J 0
(-2600 2400);
PAINT MONO (-2600 2400);
DISPLAY INVISIBLE (-2600 2400);
FORCEPROP 1 LAST $LOCATION C350
J 0
(-2550 2600);
DISPLAY 1.021277 (-2550 2600);
DISPLAY INVISIBLE (-2550 2600);
FORCEPROP 2 LAST CDS_LOCATION C350
J 0
(-2550 2600);
DISPLAY 1.021277 (-2550 2600);
DISPLAY INVISIBLE (-2550 2600);
FORCEPROP 2 LAST $SEC 1
J 0
(-2550 2600);
DISPLAY 0.680851 (-2550 2600);
PAINT MONO (-2550 2600);
DISPLAY INVISIBLE (-2550 2600);
FORCEPROP 2 LAST CDS_SEC 1
J 0
(-2550 2600);
DISPLAY 1.021277 (-2550 2600);
DISPLAY INVISIBLE (-2550 2600);
FORCEPROP 1 LAST PATH I33
J 0
(-2550 2550);
DISPLAY 0.978723 (-2550 2550);
PAINT WHITE (-2550 2550);
DISPLAY INVISIBLE (-2550 2550);
FORCEADD Q_CAP..1
(-2150 2400);
FORCEPROP 1 LAST PART_NUMBER CH647KMEA04
J 0
(-2100 2250);
DISPLAY 0.638298 (-2100 2250);
DISPLAY INVISIBLE (-2100 2250);
FORCEPROP 1 LAST VOLTAGE 4V
J 0
(-2100 2400);
DISPLAY 0.638298 (-2100 2400);
FORCEPROP 1 LAST TOLERANCE 20%
J 0
(-2100 2350);
DISPLAY 0.638298 (-2100 2350);
FORCEPROP 1 LAST PACK_TYPE C0805
J 0
(-2100 2200);
DISPLAY 0.638298 (-2100 2200);
FORCEPROP 1 LAST MATERIAL X6S
J 0
(-2100 2300);
DISPLAY 0.638298 (-2100 2300);
FORCEPROP 1 LAST VALUE 47UF
J 0
(-2100 2450);
DISPLAY 0.638298 (-2100 2450);
FORCEPROP 1 LAST $LOCATION C352
J 0
(-2100 2500);
DISPLAY 0.638298 (-2100 2500);
FORCEPROP 1 LASTPIN (-2150 2500) $PN 1
J 0
(-2140 2480);
DISPLAY 0.787234 (-2140 2480);
FORCEPROP 1 LASTPIN (-2150 2300) $PN 2
J 0
(-2140 2280);
DISPLAY 0.787234 (-2140 2280);
FORCEPROP 2 LAST CDS_LIB pure_quanta
J 0
(-2150 2400);
PAINT MONO (-2150 2400);
DISPLAY INVISIBLE (-2150 2400);
FORCEPROP 1 LAST $LOCATION C352
J 0
(-2100 2600);
DISPLAY 1.021277 (-2100 2600);
DISPLAY INVISIBLE (-2100 2600);
FORCEPROP 2 LAST CDS_LOCATION C352
J 0
(-2100 2600);
DISPLAY 1.021277 (-2100 2600);
DISPLAY INVISIBLE (-2100 2600);
FORCEPROP 2 LAST $SEC 1
J 0
(-2100 2600);
DISPLAY 0.680851 (-2100 2600);
PAINT MONO (-2100 2600);
DISPLAY INVISIBLE (-2100 2600);
FORCEPROP 2 LAST CDS_SEC 1
J 0
(-2100 2600);
DISPLAY 1.021277 (-2100 2600);
DISPLAY INVISIBLE (-2100 2600);
FORCEPROP 1 LAST PATH I34
J 0
(-2100 2550);
DISPLAY 0.978723 (-2100 2550);
PAINT WHITE (-2100 2550);
DISPLAY INVISIBLE (-2100 2550);
FORCEADD Q_CAP..1
(-1700 2400);
FORCEPROP 1 LAST PART_NUMBER CH647KMEA04
J 0
(-1650 2250);
DISPLAY 0.638298 (-1650 2250);
DISPLAY INVISIBLE (-1650 2250);
FORCEPROP 1 LAST VOLTAGE 4V
J 0
(-1650 2400);
DISPLAY 0.638298 (-1650 2400);
FORCEPROP 1 LAST TOLERANCE 20%
J 0
(-1650 2350);
DISPLAY 0.638298 (-1650 2350);
FORCEPROP 1 LAST PACK_TYPE C0805
J 0
(-1650 2200);
DISPLAY 0.638298 (-1650 2200);
FORCEPROP 1 LAST MATERIAL X6S
J 0
(-1650 2300);
DISPLAY 0.638298 (-1650 2300);
FORCEPROP 1 LAST VALUE 47UF
J 0
(-1650 2450);
DISPLAY 0.638298 (-1650 2450);
FORCEPROP 1 LAST $LOCATION C354
J 0
(-1650 2500);
DISPLAY 0.638298 (-1650 2500);
FORCEPROP 1 LASTPIN (-1700 2500) $PN 1
J 0
(-1690 2480);
DISPLAY 0.787234 (-1690 2480);
FORCEPROP 1 LASTPIN (-1700 2300) $PN 2
J 0
(-1690 2280);
DISPLAY 0.787234 (-1690 2280);
FORCEPROP 2 LAST CDS_LIB pure_quanta
J 0
(-1700 2400);
PAINT MONO (-1700 2400);
DISPLAY INVISIBLE (-1700 2400);
FORCEPROP 1 LAST $LOCATION C354
J 0
(-1650 2600);
DISPLAY 1.021277 (-1650 2600);
DISPLAY INVISIBLE (-1650 2600);
FORCEPROP 2 LAST CDS_LOCATION C354
J 0
(-1650 2600);
DISPLAY 1.021277 (-1650 2600);
DISPLAY INVISIBLE (-1650 2600);
FORCEPROP 2 LAST $SEC 1
J 0
(-1650 2600);
DISPLAY 0.680851 (-1650 2600);
PAINT MONO (-1650 2600);
DISPLAY INVISIBLE (-1650 2600);
FORCEPROP 2 LAST CDS_SEC 1
J 0
(-1650 2600);
DISPLAY 1.021277 (-1650 2600);
DISPLAY INVISIBLE (-1650 2600);
FORCEPROP 1 LAST PATH I35
J 0
(-1650 2550);
DISPLAY 0.978723 (-1650 2550);
PAINT WHITE (-1650 2550);
DISPLAY INVISIBLE (-1650 2550);
FORCEADD UNIVERSAL_POWER..1
(-4400 2675);
FORCEPROP 3 LASTPIN (-4400 2625) SIG_NAME PVCCIN_CPU1\g
J 0
(-4390 2635);
DISPLAY 0.659574 (-4390 2635);
PAINT MONO (-4390 2635);
DISPLAY INVISIBLE (-4390 2635);
FORCEPROP 1 LAST HDL_POWER PVCCIN_CPU1
J 1
(-4200 2725);
DISPLAY 0.872340 (-4200 2725);
PAINT GREEN (-4200 2725);
FORCEPROP 2 LAST CDS_LIB logical_power
J 0
(-4400 2675);
DISPLAY INVISIBLE (-4400 2675);
FORCEPROP 1 LAST PATH I36
J 0
(-4350 2700);
DISPLAY 0.872340 (-4350 2700);
PAINT AQUA (-4350 2700);
DISPLAY INVISIBLE (-4350 2700);
FORCEADD Q_CAP..1
(-1275 -2375);
FORCEPROP 1 LAST PART_NUMBER CH647KMEA04
J 0
(-1225 -2525);
DISPLAY 0.638298 (-1225 -2525);
DISPLAY INVISIBLE (-1225 -2525);
FORCEPROP 1 LAST VOLTAGE 4V
J 0
(-1225 -2375);
DISPLAY 0.638298 (-1225 -2375);
FORCEPROP 1 LAST TOLERANCE 20%
J 0
(-1225 -2425);
DISPLAY 0.638298 (-1225 -2425);
FORCEPROP 1 LAST PACK_TYPE C0805
J 0
(-1225 -2575);
DISPLAY 0.638298 (-1225 -2575);
FORCEPROP 1 LAST MATERIAL X6S
J 0
(-1225 -2475);
DISPLAY 0.638298 (-1225 -2475);
FORCEPROP 1 LAST VALUE 47UF
J 0
(-1225 -2325);
DISPLAY 0.638298 (-1225 -2325);
FORCEPROP 1 LAST $LOCATION C476
J 0
(-1225 -2275);
DISPLAY 0.978723 (-1225 -2275);
FORCEPROP 1 LASTPIN (-1275 -2275) $PN 1
J 0
(-1265 -2295);
DISPLAY 0.787234 (-1265 -2295);
FORCEPROP 1 LASTPIN (-1275 -2475) $PN 2
J 0
(-1265 -2495);
DISPLAY 0.787234 (-1265 -2495);
FORCEPROP 2 LAST CDS_LIB pure_quanta
J 0
(-1275 -2375);
PAINT MONO (-1275 -2375);
DISPLAY INVISIBLE (-1275 -2375);
FORCEPROP 2 LAST CDS_LOCATION C476
J 0
(-1225 -2175);
DISPLAY 1.021277 (-1225 -2175);
DISPLAY INVISIBLE (-1225 -2175);
FORCEPROP 2 LAST $SEC 1
J 0
(-1225 -2175);
DISPLAY 0.680851 (-1225 -2175);
PAINT MONO (-1225 -2175);
DISPLAY INVISIBLE (-1225 -2175);
FORCEPROP 2 LAST CDS_SEC 1
J 0
(-1225 -2175);
DISPLAY 1.021277 (-1225 -2175);
DISPLAY INVISIBLE (-1225 -2175);
FORCEPROP 1 LAST PATH I37
J 0
(-1225 -2225);
DISPLAY 0.978723 (-1225 -2225);
PAINT WHITE (-1225 -2225);
DISPLAY INVISIBLE (-1225 -2225);
FORCEADD Q_CAP..1
(-825 -2375);
FORCEPROP 1 LAST PART_NUMBER CH647KMEA04
J 0
(-775 -2525);
DISPLAY 0.638298 (-775 -2525);
DISPLAY INVISIBLE (-775 -2525);
FORCEPROP 1 LAST VOLTAGE 4V
J 0
(-775 -2375);
DISPLAY 0.638298 (-775 -2375);
FORCEPROP 1 LAST TOLERANCE 20%
J 0
(-775 -2425);
DISPLAY 0.638298 (-775 -2425);
FORCEPROP 1 LAST PACK_TYPE C0805
J 0
(-775 -2575);
DISPLAY 0.638298 (-775 -2575);
FORCEPROP 1 LAST MATERIAL X6S
J 0
(-775 -2475);
DISPLAY 0.638298 (-775 -2475);
FORCEPROP 1 LAST VALUE 47UF
J 0
(-775 -2325);
DISPLAY 0.638298 (-775 -2325);
FORCEPROP 1 LAST $LOCATION C477
J 0
(-775 -2275);
DISPLAY 0.978723 (-775 -2275);
FORCEPROP 1 LASTPIN (-825 -2275) $PN 1
J 0
(-815 -2295);
DISPLAY 0.787234 (-815 -2295);
FORCEPROP 1 LASTPIN (-825 -2475) $PN 2
J 0
(-815 -2495);
DISPLAY 0.787234 (-815 -2495);
FORCEPROP 2 LAST CDS_LIB pure_quanta
J 0
(-825 -2375);
PAINT MONO (-825 -2375);
DISPLAY INVISIBLE (-825 -2375);
FORCEPROP 2 LAST CDS_LOCATION C477
J 0
(-775 -2175);
DISPLAY 1.021277 (-775 -2175);
DISPLAY INVISIBLE (-775 -2175);
FORCEPROP 2 LAST $SEC 1
J 0
(-775 -2175);
DISPLAY 0.680851 (-775 -2175);
PAINT MONO (-775 -2175);
DISPLAY INVISIBLE (-775 -2175);
FORCEPROP 2 LAST CDS_SEC 1
J 0
(-775 -2175);
DISPLAY 1.021277 (-775 -2175);
DISPLAY INVISIBLE (-775 -2175);
FORCEPROP 1 LAST PATH I38
J 0
(-775 -2225);
DISPLAY 0.978723 (-775 -2225);
PAINT WHITE (-775 -2225);
DISPLAY INVISIBLE (-775 -2225);
FORCEADD Q_CAP..1
(-375 -2375);
FORCEPROP 1 LAST PART_NUMBER CH647KMEA04
J 0
(-325 -2525);
DISPLAY 0.638298 (-325 -2525);
DISPLAY INVISIBLE (-325 -2525);
FORCEPROP 1 LAST VOLTAGE 4V
J 0
(-325 -2375);
DISPLAY 0.638298 (-325 -2375);
FORCEPROP 1 LAST TOLERANCE 20%
J 0
(-325 -2425);
DISPLAY 0.638298 (-325 -2425);
FORCEPROP 1 LAST PACK_TYPE C0805
J 0
(-325 -2575);
DISPLAY 0.638298 (-325 -2575);
FORCEPROP 1 LAST MATERIAL X6S
J 0
(-325 -2475);
DISPLAY 0.638298 (-325 -2475);
FORCEPROP 1 LAST VALUE 47UF
J 0
(-325 -2325);
DISPLAY 0.638298 (-325 -2325);
FORCEPROP 1 LAST $LOCATION C479
J 0
(-325 -2275);
DISPLAY 0.978723 (-325 -2275);
FORCEPROP 1 LASTPIN (-375 -2275) $PN 1
J 0
(-365 -2295);
DISPLAY 0.787234 (-365 -2295);
FORCEPROP 1 LASTPIN (-375 -2475) $PN 2
J 0
(-365 -2495);
DISPLAY 0.787234 (-365 -2495);
FORCEPROP 2 LAST CDS_LIB pure_quanta
J 0
(-375 -2375);
PAINT MONO (-375 -2375);
DISPLAY INVISIBLE (-375 -2375);
FORCEPROP 2 LAST CDS_LOCATION C479
J 0
(-325 -2175);
DISPLAY 1.021277 (-325 -2175);
DISPLAY INVISIBLE (-325 -2175);
FORCEPROP 2 LAST $SEC 1
J 0
(-325 -2175);
DISPLAY 0.680851 (-325 -2175);
PAINT MONO (-325 -2175);
DISPLAY INVISIBLE (-325 -2175);
FORCEPROP 2 LAST CDS_SEC 1
J 0
(-325 -2175);
DISPLAY 1.021277 (-325 -2175);
DISPLAY INVISIBLE (-325 -2175);
FORCEPROP 1 LAST PATH I39
J 0
(-325 -2225);
DISPLAY 0.978723 (-325 -2225);
PAINT WHITE (-325 -2225);
DISPLAY INVISIBLE (-325 -2225);
FORCEADD Q_CAP..1
(-3525 -2375);
FORCEPROP 1 LAST PART_NUMBER CH647KMEA04
J 0
(-3475 -2525);
DISPLAY 0.638298 (-3475 -2525);
DISPLAY INVISIBLE (-3475 -2525);
FORCEPROP 1 LAST VOLTAGE 4V
J 0
(-3475 -2375);
DISPLAY 0.638298 (-3475 -2375);
FORCEPROP 1 LAST TOLERANCE 20%
J 0
(-3475 -2425);
DISPLAY 0.638298 (-3475 -2425);
FORCEPROP 1 LAST PACK_TYPE C0805
J 0
(-3475 -2575);
DISPLAY 0.638298 (-3475 -2575);
FORCEPROP 1 LAST VALUE 47UF
J 0
(-3475 -2325);
DISPLAY 0.638298 (-3475 -2325);
FORCEPROP 1 LAST MATERIAL X6S
J 0
(-3475 -2475);
DISPLAY 0.638298 (-3475 -2475);
FORCEPROP 1 LAST $LOCATION C458
J 0
(-3475 -2275);
DISPLAY 0.978723 (-3475 -2275);
FORCEPROP 1 LASTPIN (-3525 -2275) $PN 1
J 0
(-3515 -2295);
DISPLAY 0.787234 (-3515 -2295);
FORCEPROP 1 LASTPIN (-3525 -2475) $PN 2
J 0
(-3515 -2495);
DISPLAY 0.787234 (-3515 -2495);
FORCEPROP 2 LAST CDS_LIB pure_quanta
J 0
(-3525 -2375);
PAINT MONO (-3525 -2375);
DISPLAY INVISIBLE (-3525 -2375);
FORCEPROP 2 LAST CDS_LOCATION C458
J 0
(-3475 -2175);
DISPLAY 1.021277 (-3475 -2175);
DISPLAY INVISIBLE (-3475 -2175);
FORCEPROP 2 LAST $SEC 1
J 0
(-3475 -2175);
DISPLAY 0.680851 (-3475 -2175);
PAINT MONO (-3475 -2175);
DISPLAY INVISIBLE (-3475 -2175);
FORCEPROP 2 LAST CDS_SEC 1
J 0
(-3475 -2175);
DISPLAY 1.021277 (-3475 -2175);
DISPLAY INVISIBLE (-3475 -2175);
FORCEPROP 1 LAST PATH I4
J 0
(-3475 -2225);
DISPLAY 0.978723 (-3475 -2225);
PAINT WHITE (-3475 -2225);
DISPLAY INVISIBLE (-3475 -2225);
FORCEADD UNIVERSAL_GND..1
(525 -2725);
FORCEPROP 3 LASTPIN (525 -2675) SIG_NAME GND\g
J 0
(535 -2665);
DISPLAY 0.659574 (535 -2665);
PAINT MONO (535 -2665);
DISPLAY INVISIBLE (535 -2665);
FORCEPROP 2 LAST CDS_LIB logical_power
J 0
(525 -2725);
PAINT MONO (525 -2725);
DISPLAY INVISIBLE (525 -2725);
FORCEPROP 1 LAST HDL_POWER GND
J 1
(550 -2800);
DISPLAY 0.872340 (550 -2800);
PAINT GREEN (550 -2800);
DISPLAY INVISIBLE (550 -2800);
FORCEPROP 1 LAST PATH I40
J 0
(600 -2725);
DISPLAY 0.872340 (600 -2725);
PAINT AQUA (600 -2725);
DISPLAY INVISIBLE (600 -2725);
FORCEADD Q_CAP..1
(75 -2375);
FORCEPROP 1 LAST PART_NUMBER CH647KMEA04
J 0
(125 -2525);
DISPLAY 0.638298 (125 -2525);
DISPLAY INVISIBLE (125 -2525);
FORCEPROP 1 LAST VOLTAGE 4V
J 0
(125 -2375);
DISPLAY 0.638298 (125 -2375);
FORCEPROP 1 LAST TOLERANCE 20%
J 0
(125 -2425);
DISPLAY 0.638298 (125 -2425);
FORCEPROP 1 LAST PACK_TYPE C0805
J 0
(125 -2575);
DISPLAY 0.638298 (125 -2575);
FORCEPROP 1 LAST MATERIAL X6S
J 0
(125 -2475);
DISPLAY 0.638298 (125 -2475);
FORCEPROP 1 LAST VALUE 47UF
J 0
(125 -2325);
DISPLAY 0.638298 (125 -2325);
FORCEPROP 1 LAST $LOCATION C482
J 0
(125 -2275);
DISPLAY 0.978723 (125 -2275);
FORCEPROP 1 LASTPIN (75 -2275) $PN 1
J 0
(85 -2295);
DISPLAY 0.787234 (85 -2295);
FORCEPROP 1 LASTPIN (75 -2475) $PN 2
J 0
(85 -2495);
DISPLAY 0.787234 (85 -2495);
FORCEPROP 2 LAST CDS_LIB pure_quanta
J 0
(75 -2375);
PAINT MONO (75 -2375);
DISPLAY INVISIBLE (75 -2375);
FORCEPROP 2 LAST CDS_LOCATION C482
J 0
(125 -2175);
DISPLAY 1.021277 (125 -2175);
DISPLAY INVISIBLE (125 -2175);
FORCEPROP 2 LAST $SEC 1
J 0
(125 -2175);
DISPLAY 0.680851 (125 -2175);
PAINT MONO (125 -2175);
DISPLAY INVISIBLE (125 -2175);
FORCEPROP 2 LAST CDS_SEC 1
J 0
(125 -2175);
DISPLAY 1.021277 (125 -2175);
DISPLAY INVISIBLE (125 -2175);
FORCEPROP 1 LAST PATH I41
J 0
(125 -2225);
DISPLAY 0.978723 (125 -2225);
PAINT WHITE (125 -2225);
DISPLAY INVISIBLE (125 -2225);
FORCEADD Q_CAP..1
(525 -2375);
FORCEPROP 1 LAST PART_NUMBER CH647KMEA04
J 0
(575 -2525);
DISPLAY 0.638298 (575 -2525);
DISPLAY INVISIBLE (575 -2525);
FORCEPROP 1 LAST VOLTAGE 4V
J 0
(575 -2375);
DISPLAY 0.638298 (575 -2375);
FORCEPROP 1 LAST TOLERANCE 20%
J 0
(575 -2425);
DISPLAY 0.638298 (575 -2425);
FORCEPROP 1 LAST PACK_TYPE C0805
J 0
(575 -2575);
DISPLAY 0.638298 (575 -2575);
FORCEPROP 1 LAST MATERIAL X6S
J 0
(575 -2475);
DISPLAY 0.638298 (575 -2475);
FORCEPROP 1 LAST VALUE 47UF
J 0
(575 -2325);
DISPLAY 0.638298 (575 -2325);
FORCEPROP 1 LAST $LOCATION C485
J 0
(575 -2275);
DISPLAY 0.978723 (575 -2275);
FORCEPROP 1 LASTPIN (525 -2275) $PN 1
J 0
(535 -2295);
DISPLAY 0.787234 (535 -2295);
FORCEPROP 1 LASTPIN (525 -2475) $PN 2
J 0
(535 -2495);
DISPLAY 0.787234 (535 -2495);
FORCEPROP 2 LAST CDS_LIB pure_quanta
J 0
(525 -2375);
PAINT MONO (525 -2375);
DISPLAY INVISIBLE (525 -2375);
FORCEPROP 2 LAST CDS_LOCATION C485
J 0
(575 -2175);
DISPLAY 1.021277 (575 -2175);
DISPLAY INVISIBLE (575 -2175);
FORCEPROP 2 LAST $SEC 1
J 0
(575 -2175);
DISPLAY 0.680851 (575 -2175);
PAINT MONO (575 -2175);
DISPLAY INVISIBLE (575 -2175);
FORCEPROP 2 LAST CDS_SEC 1
J 0
(575 -2175);
DISPLAY 1.021277 (575 -2175);
DISPLAY INVISIBLE (575 -2175);
FORCEPROP 1 LAST PATH I42
J 0
(575 -2225);
DISPLAY 0.978723 (575 -2225);
PAINT WHITE (575 -2225);
DISPLAY INVISIBLE (575 -2225);
FORCEADD Q_CAP..1
(-1175 1450);
FORCEPROP 1 LAST PART_NUMBER CH647KMEA04
J 0
(-1125 1300);
DISPLAY 0.638298 (-1125 1300);
DISPLAY INVISIBLE (-1125 1300);
FORCEPROP 1 LAST VOLTAGE 4V
J 0
(-1125 1450);
DISPLAY 0.638298 (-1125 1450);
FORCEPROP 1 LAST MATERIAL X6S
J 0
(-1125 1350);
DISPLAY 0.638298 (-1125 1350);
FORCEPROP 1 LAST TOLERANCE 20%
J 0
(-1125 1400);
DISPLAY 0.638298 (-1125 1400);
FORCEPROP 1 LAST VALUE 47UF
J 0
(-1125 1500);
DISPLAY 0.638298 (-1125 1500);
FORCEPROP 1 LAST PACK_TYPE C0805
J 0
(-1125 1250);
DISPLAY 0.638298 (-1125 1250);
FORCEPROP 1 LAST $LOCATION C1403
J 0
(-1125 1550);
DISPLAY 0.978723 (-1125 1550);
FORCEPROP 1 LASTPIN (-1175 1550) $PN 1
J 0
(-1165 1530);
DISPLAY 0.787234 (-1165 1530);
FORCEPROP 1 LASTPIN (-1175 1350) $PN 2
J 0
(-1165 1330);
DISPLAY 0.787234 (-1165 1330);
FORCEPROP 2 LAST CDS_LIB pure_quanta
J 0
(-1175 1450);
PAINT MONO (-1175 1450);
DISPLAY INVISIBLE (-1175 1450);
FORCEPROP 2 LAST CDS_LOCATION C1403
J 0
(-1125 1650);
DISPLAY 1.021277 (-1125 1650);
DISPLAY INVISIBLE (-1125 1650);
FORCEPROP 2 LAST $SEC 1
J 0
(-1125 1650);
DISPLAY 0.680851 (-1125 1650);
PAINT MONO (-1125 1650);
DISPLAY INVISIBLE (-1125 1650);
FORCEPROP 2 LAST CDS_SEC 1
J 0
(-1125 1650);
DISPLAY 1.021277 (-1125 1650);
DISPLAY INVISIBLE (-1125 1650);
FORCEPROP 1 LAST PATH I43
J 0
(-1125 1600);
DISPLAY 0.978723 (-1125 1600);
PAINT WHITE (-1125 1600);
DISPLAY INVISIBLE (-1125 1600);
FORCEADD Q_CAP..1
(-725 1450);
FORCEPROP 1 LAST PART_NUMBER CH647KMEA04
J 0
(-675 1300);
DISPLAY 0.638298 (-675 1300);
DISPLAY INVISIBLE (-675 1300);
FORCEPROP 1 LAST VOLTAGE 4V
J 0
(-675 1450);
DISPLAY 0.638298 (-675 1450);
FORCEPROP 1 LAST MATERIAL X6S
J 0
(-675 1350);
DISPLAY 0.638298 (-675 1350);
FORCEPROP 1 LAST TOLERANCE 20%
J 0
(-675 1400);
DISPLAY 0.638298 (-675 1400);
FORCEPROP 1 LAST VALUE 47UF
J 0
(-675 1500);
DISPLAY 0.638298 (-675 1500);
FORCEPROP 1 LAST PACK_TYPE C0805
J 0
(-675 1250);
DISPLAY 0.638298 (-675 1250);
FORCEPROP 1 LAST $LOCATION C1404
J 0
(-675 1550);
DISPLAY 0.978723 (-675 1550);
FORCEPROP 1 LASTPIN (-725 1550) $PN 1
J 0
(-715 1530);
DISPLAY 0.787234 (-715 1530);
PAINT MONO (-715 1530);
FORCEPROP 1 LASTPIN (-725 1350) $PN 2
J 0
(-715 1330);
DISPLAY 0.787234 (-715 1330);
PAINT MONO (-715 1330);
FORCEPROP 2 LAST CDS_LIB pure_quanta
J 0
(-725 1450);
DISPLAY INVISIBLE (-725 1450);
FORCEPROP 2 LAST CDS_LOCATION C1404
J 0
(-675 1650);
DISPLAY 1.021277 (-675 1650);
DISPLAY INVISIBLE (-675 1650);
FORCEPROP 0 LAST $SEC 1
J 0
(-675 1600);
DISPLAY 0.680851 (-675 1600);
PAINT MONO (-675 1600);
DISPLAY INVISIBLE (-675 1600);
FORCEPROP 2 LAST CDS_SEC 1
J 0
(-675 1650);
DISPLAY 1.021277 (-675 1650);
DISPLAY INVISIBLE (-675 1650);
FORCEPROP 1 LAST PATH I44
J 0
(-675 1600);
DISPLAY 0.978723 (-675 1600);
PAINT WHITE (-675 1600);
DISPLAY INVISIBLE (-675 1600);
FORCEADD UNIVERSAL_POWER..1
(-1175 1725);
FORCEPROP 3 LASTPIN (-1175 1675) SIG_NAME PVNN_MAIN_CPU1\g
J 0
(-1165 1685);
DISPLAY 0.659574 (-1165 1685);
PAINT MONO (-1165 1685);
DISPLAY INVISIBLE (-1165 1685);
FORCEPROP 1 LAST HDL_POWER PVNN_MAIN_CPU1
J 1
(-975 1775);
DISPLAY 0.872340 (-975 1775);
PAINT GREEN (-975 1775);
FORCEPROP 2 LAST CDS_LIB logical_power
J 0
(-1175 1725);
PAINT MONO (-1175 1725);
DISPLAY INVISIBLE (-1175 1725);
FORCEPROP 1 LAST PATH I45
J 0
(-1125 1750);
DISPLAY 0.872340 (-1125 1750);
PAINT AQUA (-1125 1750);
DISPLAY INVISIBLE (-1125 1750);
FORCEADD Q_CAP..1
(-1250 2400);
FORCEPROP 1 LAST PART_NUMBER CH647KMEA04
J 0
(-1200 2250);
DISPLAY 0.638298 (-1200 2250);
DISPLAY INVISIBLE (-1200 2250);
FORCEPROP 1 LAST VOLTAGE 4V
J 0
(-1200 2400);
DISPLAY 0.638298 (-1200 2400);
FORCEPROP 1 LAST TOLERANCE 20%
J 0
(-1200 2350);
DISPLAY 0.638298 (-1200 2350);
FORCEPROP 1 LAST PACK_TYPE C0805
J 0
(-1200 2200);
DISPLAY 0.638298 (-1200 2200);
FORCEPROP 1 LAST MATERIAL X6S
J 0
(-1200 2300);
DISPLAY 0.638298 (-1200 2300);
FORCEPROP 1 LAST VALUE 47UF
J 0
(-1200 2450);
DISPLAY 0.638298 (-1200 2450);
FORCEPROP 1 LAST $LOCATION C322
J 0
(-1200 2500);
DISPLAY 0.638298 (-1200 2500);
FORCEPROP 1 LASTPIN (-1250 2500) $PN 1
J 0
(-1240 2480);
DISPLAY 0.787234 (-1240 2480);
FORCEPROP 1 LASTPIN (-1250 2300) $PN 2
J 0
(-1240 2280);
DISPLAY 0.787234 (-1240 2280);
FORCEPROP 2 LAST CDS_LIB pure_quanta
J 0
(-1250 2400);
PAINT MONO (-1250 2400);
DISPLAY INVISIBLE (-1250 2400);
FORCEPROP 1 LAST $LOCATION C322
J 0
(-1200 2600);
DISPLAY 1.021277 (-1200 2600);
DISPLAY INVISIBLE (-1200 2600);
FORCEPROP 2 LAST CDS_LOCATION C322
J 0
(-1200 2600);
DISPLAY 1.021277 (-1200 2600);
DISPLAY INVISIBLE (-1200 2600);
FORCEPROP 2 LAST $SEC 1
J 0
(-1200 2600);
DISPLAY 0.680851 (-1200 2600);
PAINT MONO (-1200 2600);
DISPLAY INVISIBLE (-1200 2600);
FORCEPROP 2 LAST CDS_SEC 1
J 0
(-1200 2600);
DISPLAY 1.021277 (-1200 2600);
DISPLAY INVISIBLE (-1200 2600);
FORCEPROP 1 LAST PATH I46
J 0
(-1200 2550);
DISPLAY 0.978723 (-1200 2550);
PAINT WHITE (-1200 2550);
DISPLAY INVISIBLE (-1200 2550);
FORCEADD Q_CAP..1
(-800 2400);
FORCEPROP 1 LAST PART_NUMBER CH647KMEA04
J 0
(-750 2250);
DISPLAY 0.638298 (-750 2250);
DISPLAY INVISIBLE (-750 2250);
FORCEPROP 1 LAST VOLTAGE 4V
J 0
(-750 2400);
DISPLAY 0.638298 (-750 2400);
FORCEPROP 1 LAST TOLERANCE 20%
J 0
(-750 2350);
DISPLAY 0.638298 (-750 2350);
FORCEPROP 1 LAST PACK_TYPE C0805
J 0
(-750 2200);
DISPLAY 0.638298 (-750 2200);
FORCEPROP 1 LAST MATERIAL X6S
J 0
(-750 2300);
DISPLAY 0.638298 (-750 2300);
FORCEPROP 1 LAST VALUE 47UF
J 0
(-750 2450);
DISPLAY 0.638298 (-750 2450);
FORCEPROP 1 LAST $LOCATION C325
J 0
(-750 2500);
DISPLAY 0.638298 (-750 2500);
FORCEPROP 1 LASTPIN (-800 2500) $PN 1
J 0
(-790 2480);
DISPLAY 0.787234 (-790 2480);
FORCEPROP 1 LASTPIN (-800 2300) $PN 2
J 0
(-790 2280);
DISPLAY 0.787234 (-790 2280);
FORCEPROP 2 LAST CDS_LIB pure_quanta
J 0
(-800 2400);
PAINT MONO (-800 2400);
DISPLAY INVISIBLE (-800 2400);
FORCEPROP 1 LAST $LOCATION C325
J 0
(-750 2600);
DISPLAY 1.021277 (-750 2600);
DISPLAY INVISIBLE (-750 2600);
FORCEPROP 2 LAST CDS_LOCATION C325
J 0
(-750 2600);
DISPLAY 1.021277 (-750 2600);
DISPLAY INVISIBLE (-750 2600);
FORCEPROP 2 LAST $SEC 1
J 0
(-750 2600);
DISPLAY 0.680851 (-750 2600);
PAINT MONO (-750 2600);
DISPLAY INVISIBLE (-750 2600);
FORCEPROP 2 LAST CDS_SEC 1
J 0
(-750 2600);
DISPLAY 1.021277 (-750 2600);
DISPLAY INVISIBLE (-750 2600);
FORCEPROP 1 LAST PATH I47
J 0
(-750 2550);
DISPLAY 0.978723 (-750 2550);
PAINT WHITE (-750 2550);
DISPLAY INVISIBLE (-750 2550);
FORCEADD UNIVERSAL_GND..1
(-325 1100);
FORCEPROP 3 LASTPIN (-325 1150) SIG_NAME GND\g
J 0
(-315 1160);
DISPLAY 0.659574 (-315 1160);
PAINT MONO (-315 1160);
DISPLAY INVISIBLE (-315 1160);
FORCEPROP 2 LAST CDS_LIB logical_power
J 0
(-325 1100);
PAINT MONO (-325 1100);
DISPLAY INVISIBLE (-325 1100);
FORCEPROP 1 LAST HDL_POWER GND
J 1
(-300 1025);
DISPLAY 0.872340 (-300 1025);
PAINT GREEN (-300 1025);
DISPLAY INVISIBLE (-300 1025);
FORCEPROP 1 LAST PATH I48
J 0
(-250 1100);
DISPLAY 0.872340 (-250 1100);
PAINT AQUA (-250 1100);
DISPLAY INVISIBLE (-250 1100);
FORCEADD Q_CAP..1
(-325 1450);
FORCEPROP 1 LAST PART_NUMBER CH622KMEB01
J 0
(-275 1300);
DISPLAY 0.638298 (-275 1300);
DISPLAY INVISIBLE (-275 1300);
FORCEPROP 1 LAST PACK_TYPE C0402
J 0
(-275 1250);
DISPLAY 0.638298 (-275 1250);
FORCEPROP 1 LAST VALUE 22UF
J 0
(-275 1500);
DISPLAY 0.638298 (-275 1500);
FORCEPROP 1 LAST VOLTAGE 4V
J 0
(-275 1450);
DISPLAY 0.638298 (-275 1450);
FORCEPROP 1 LAST MATERIAL X6S
J 0
(-275 1350);
DISPLAY 0.638298 (-275 1350);
FORCEPROP 1 LAST TOLERANCE 20%
J 0
(-275 1400);
DISPLAY 0.638298 (-275 1400);
FORCEPROP 1 LAST $LOCATION C1353
J 0
(-275 1550);
DISPLAY 0.787234 (-275 1550);
FORCEPROP 1 LASTPIN (-325 1550) $PN 1
J 0
(-315 1530);
DISPLAY 0.787234 (-315 1530);
PAINT MONO (-315 1530);
FORCEPROP 1 LASTPIN (-325 1350) $PN 2
J 0
(-315 1330);
DISPLAY 0.787234 (-315 1330);
PAINT MONO (-315 1330);
FORCEPROP 2 LAST CDS_LIB pure_quanta
J 0
(-325 1450);
DISPLAY INVISIBLE (-325 1450);
FORCEPROP 0 LAST CDS_LOCATION C1353
J 0
(-275 1600);
DISPLAY 1.021277 (-275 1600);
DISPLAY INVISIBLE (-275 1600);
FORCEPROP 0 LAST $SEC 1
J 0
(-275 1600);
DISPLAY 0.680851 (-275 1600);
PAINT MONO (-275 1600);
DISPLAY INVISIBLE (-275 1600);
FORCEPROP 0 LAST CDS_SEC 1
J 0
(-275 1600);
DISPLAY 1.021277 (-275 1600);
DISPLAY INVISIBLE (-275 1600);
FORCEPROP 1 LAST PATH I49
J 0
(-275 1600);
DISPLAY 0.978723 (-275 1600);
PAINT WHITE (-275 1600);
DISPLAY INVISIBLE (-275 1600);
FORCEADD Q_CAP..1
(-3075 -2375);
FORCEPROP 1 LAST PART_NUMBER CH647KMEA04
J 0
(-3025 -2525);
DISPLAY 0.638298 (-3025 -2525);
DISPLAY INVISIBLE (-3025 -2525);
FORCEPROP 1 LAST VOLTAGE 4V
J 0
(-3025 -2375);
DISPLAY 0.638298 (-3025 -2375);
FORCEPROP 1 LAST TOLERANCE 20%
J 0
(-3025 -2425);
DISPLAY 0.638298 (-3025 -2425);
FORCEPROP 1 LAST PACK_TYPE C0805
J 0
(-3025 -2575);
DISPLAY 0.638298 (-3025 -2575);
FORCEPROP 1 LAST MATERIAL X6S
J 0
(-3025 -2475);
DISPLAY 0.638298 (-3025 -2475);
FORCEPROP 1 LAST VALUE 47UF
J 0
(-3025 -2325);
DISPLAY 0.638298 (-3025 -2325);
FORCEPROP 1 LAST $LOCATION C462
J 0
(-3025 -2275);
DISPLAY 0.978723 (-3025 -2275);
FORCEPROP 1 LASTPIN (-3075 -2275) $PN 1
J 0
(-3065 -2295);
DISPLAY 0.787234 (-3065 -2295);
FORCEPROP 1 LASTPIN (-3075 -2475) $PN 2
J 0
(-3065 -2495);
DISPLAY 0.787234 (-3065 -2495);
FORCEPROP 2 LAST CDS_LIB pure_quanta
J 0
(-3075 -2375);
PAINT MONO (-3075 -2375);
DISPLAY INVISIBLE (-3075 -2375);
FORCEPROP 2 LAST CDS_LOCATION C462
J 0
(-3025 -2175);
DISPLAY 1.021277 (-3025 -2175);
DISPLAY INVISIBLE (-3025 -2175);
FORCEPROP 2 LAST $SEC 1
J 0
(-3025 -2175);
DISPLAY 0.680851 (-3025 -2175);
PAINT MONO (-3025 -2175);
DISPLAY INVISIBLE (-3025 -2175);
FORCEPROP 2 LAST CDS_SEC 1
J 0
(-3025 -2175);
DISPLAY 1.021277 (-3025 -2175);
DISPLAY INVISIBLE (-3025 -2175);
FORCEPROP 1 LAST PATH I5
J 0
(-3025 -2225);
DISPLAY 0.978723 (-3025 -2225);
PAINT WHITE (-3025 -2225);
DISPLAY INVISIBLE (-3025 -2225);
FORCEADD Q_CAP..1
(-350 2400);
FORCEPROP 1 LAST PART_NUMBER CH647KMEA04
J 0
(-300 2250);
DISPLAY 0.638298 (-300 2250);
DISPLAY INVISIBLE (-300 2250);
FORCEPROP 1 LAST VOLTAGE 4V
J 0
(-300 2400);
DISPLAY 0.638298 (-300 2400);
FORCEPROP 1 LAST TOLERANCE 20%
J 0
(-300 2350);
DISPLAY 0.638298 (-300 2350);
FORCEPROP 1 LAST PACK_TYPE C0805
J 0
(-300 2200);
DISPLAY 0.638298 (-300 2200);
FORCEPROP 1 LAST MATERIAL X6S
J 0
(-300 2300);
DISPLAY 0.638298 (-300 2300);
FORCEPROP 1 LAST VALUE 47UF
J 0
(-300 2450);
DISPLAY 0.638298 (-300 2450);
FORCEPROP 1 LAST $LOCATION C328
J 0
(-300 2500);
DISPLAY 0.638298 (-300 2500);
FORCEPROP 1 LASTPIN (-350 2500) $PN 1
J 0
(-340 2480);
DISPLAY 0.787234 (-340 2480);
FORCEPROP 1 LASTPIN (-350 2300) $PN 2
J 0
(-340 2280);
DISPLAY 0.787234 (-340 2280);
FORCEPROP 2 LAST CDS_LIB pure_quanta
J 0
(-350 2400);
PAINT MONO (-350 2400);
DISPLAY INVISIBLE (-350 2400);
FORCEPROP 1 LAST $LOCATION C328
J 0
(-300 2600);
DISPLAY 1.021277 (-300 2600);
DISPLAY INVISIBLE (-300 2600);
FORCEPROP 2 LAST CDS_LOCATION C328
J 0
(-300 2600);
DISPLAY 1.021277 (-300 2600);
DISPLAY INVISIBLE (-300 2600);
FORCEPROP 2 LAST $SEC 1
J 0
(-300 2600);
DISPLAY 0.680851 (-300 2600);
PAINT MONO (-300 2600);
DISPLAY INVISIBLE (-300 2600);
FORCEPROP 2 LAST CDS_SEC 1
J 0
(-300 2600);
DISPLAY 1.021277 (-300 2600);
DISPLAY INVISIBLE (-300 2600);
FORCEPROP 1 LAST PATH I50
J 0
(-300 2550);
DISPLAY 0.978723 (-300 2550);
PAINT WHITE (-300 2550);
DISPLAY INVISIBLE (-300 2550);
FORCEADD Q_CAP..1
(100 2400);
FORCEPROP 1 LAST PART_NUMBER CH647KMEA04
J 0
(150 2250);
DISPLAY 0.638298 (150 2250);
DISPLAY INVISIBLE (150 2250);
FORCEPROP 1 LAST VOLTAGE 4V
J 0
(150 2400);
DISPLAY 0.638298 (150 2400);
FORCEPROP 1 LAST TOLERANCE 20%
J 0
(150 2350);
DISPLAY 0.638298 (150 2350);
FORCEPROP 1 LAST PACK_TYPE C0805
J 0
(150 2200);
DISPLAY 0.638298 (150 2200);
FORCEPROP 1 LAST MATERIAL X6S
J 0
(150 2300);
DISPLAY 0.638298 (150 2300);
FORCEPROP 1 LAST VALUE 47UF
J 0
(150 2450);
DISPLAY 0.638298 (150 2450);
FORCEPROP 1 LAST $LOCATION C341
J 0
(150 2500);
DISPLAY 0.638298 (150 2500);
FORCEPROP 1 LASTPIN (100 2500) $PN 1
J 0
(110 2480);
DISPLAY 0.787234 (110 2480);
FORCEPROP 1 LASTPIN (100 2300) $PN 2
J 0
(110 2280);
DISPLAY 0.787234 (110 2280);
FORCEPROP 2 LAST CDS_LIB pure_quanta
J 0
(100 2400);
PAINT MONO (100 2400);
DISPLAY INVISIBLE (100 2400);
FORCEPROP 1 LAST $LOCATION C341
J 0
(150 2600);
DISPLAY 1.021277 (150 2600);
DISPLAY INVISIBLE (150 2600);
FORCEPROP 2 LAST CDS_LOCATION C341
J 0
(150 2600);
DISPLAY 1.021277 (150 2600);
DISPLAY INVISIBLE (150 2600);
FORCEPROP 2 LAST $SEC 1
J 0
(150 2600);
DISPLAY 0.680851 (150 2600);
PAINT MONO (150 2600);
DISPLAY INVISIBLE (150 2600);
FORCEPROP 2 LAST CDS_SEC 1
J 0
(150 2600);
DISPLAY 1.021277 (150 2600);
DISPLAY INVISIBLE (150 2600);
FORCEPROP 1 LAST PATH I51
J 0
(150 2550);
DISPLAY 0.978723 (150 2550);
PAINT WHITE (150 2550);
DISPLAY INVISIBLE (150 2550);
FORCEADD Q_CAP..1
(550 2400);
FORCEPROP 1 LAST PART_NUMBER CH647KMEA04
J 0
(600 2250);
DISPLAY 0.638298 (600 2250);
DISPLAY INVISIBLE (600 2250);
FORCEPROP 1 LAST VOLTAGE 4V
J 0
(600 2400);
DISPLAY 0.638298 (600 2400);
FORCEPROP 1 LAST TOLERANCE 20%
J 0
(600 2350);
DISPLAY 0.638298 (600 2350);
FORCEPROP 1 LAST PACK_TYPE C0805
J 0
(600 2200);
DISPLAY 0.638298 (600 2200);
FORCEPROP 1 LAST MATERIAL X6S
J 0
(600 2300);
DISPLAY 0.638298 (600 2300);
FORCEPROP 1 LAST VALUE 47UF
J 0
(600 2450);
DISPLAY 0.638298 (600 2450);
FORCEPROP 1 LAST $LOCATION C343
J 0
(600 2500);
DISPLAY 0.638298 (600 2500);
FORCEPROP 1 LASTPIN (550 2500) $PN 1
J 0
(560 2480);
DISPLAY 0.787234 (560 2480);
FORCEPROP 1 LASTPIN (550 2300) $PN 2
J 0
(560 2280);
DISPLAY 0.787234 (560 2280);
FORCEPROP 2 LAST CDS_LIB pure_quanta
J 0
(550 2400);
PAINT MONO (550 2400);
DISPLAY INVISIBLE (550 2400);
FORCEPROP 1 LAST $LOCATION C343
J 0
(600 2600);
DISPLAY 1.021277 (600 2600);
DISPLAY INVISIBLE (600 2600);
FORCEPROP 2 LAST CDS_LOCATION C343
J 0
(600 2600);
DISPLAY 1.021277 (600 2600);
DISPLAY INVISIBLE (600 2600);
FORCEPROP 2 LAST $SEC 1
J 0
(600 2600);
DISPLAY 0.680851 (600 2600);
PAINT MONO (600 2600);
DISPLAY INVISIBLE (600 2600);
FORCEPROP 2 LAST CDS_SEC 1
J 0
(600 2600);
DISPLAY 1.021277 (600 2600);
DISPLAY INVISIBLE (600 2600);
FORCEPROP 1 LAST PATH I52
J 0
(600 2550);
DISPLAY 0.978723 (600 2550);
PAINT WHITE (600 2550);
DISPLAY INVISIBLE (600 2550);
FORCEADD Q_CAP..1
(1000 2400);
FORCEPROP 1 LAST PART_NUMBER CH647KMEA04
J 0
(1050 2250);
DISPLAY 0.638298 (1050 2250);
DISPLAY INVISIBLE (1050 2250);
FORCEPROP 1 LAST VOLTAGE 4V
J 0
(1050 2400);
DISPLAY 0.638298 (1050 2400);
FORCEPROP 1 LAST TOLERANCE 20%
J 0
(1050 2350);
DISPLAY 0.638298 (1050 2350);
FORCEPROP 1 LAST PACK_TYPE C0805
J 0
(1050 2200);
DISPLAY 0.638298 (1050 2200);
FORCEPROP 1 LAST MATERIAL X6S
J 0
(1050 2300);
DISPLAY 0.638298 (1050 2300);
FORCEPROP 1 LAST VALUE 47UF
J 0
(1050 2450);
DISPLAY 0.638298 (1050 2450);
FORCEPROP 1 LAST $LOCATION C345
J 0
(1050 2500);
DISPLAY 0.638298 (1050 2500);
FORCEPROP 1 LASTPIN (1000 2500) $PN 1
J 0
(1010 2480);
DISPLAY 0.787234 (1010 2480);
FORCEPROP 1 LASTPIN (1000 2300) $PN 2
J 0
(1010 2280);
DISPLAY 0.787234 (1010 2280);
FORCEPROP 2 LAST CDS_LIB pure_quanta
J 0
(1000 2400);
PAINT MONO (1000 2400);
DISPLAY INVISIBLE (1000 2400);
FORCEPROP 1 LAST $LOCATION C345
J 0
(1050 2600);
DISPLAY 1.021277 (1050 2600);
DISPLAY INVISIBLE (1050 2600);
FORCEPROP 2 LAST CDS_LOCATION C345
J 0
(1050 2600);
DISPLAY 1.021277 (1050 2600);
DISPLAY INVISIBLE (1050 2600);
FORCEPROP 2 LAST $SEC 1
J 0
(1050 2600);
DISPLAY 0.680851 (1050 2600);
PAINT MONO (1050 2600);
DISPLAY INVISIBLE (1050 2600);
FORCEPROP 2 LAST CDS_SEC 1
J 0
(1050 2600);
DISPLAY 1.021277 (1050 2600);
DISPLAY INVISIBLE (1050 2600);
FORCEPROP 1 LAST PATH I53
J 0
(1050 2550);
DISPLAY 0.978723 (1050 2550);
PAINT WHITE (1050 2550);
DISPLAY INVISIBLE (1050 2550);
FORCEADD UNIVERSAL_GND..1
(1450 2075);
FORCEPROP 3 LASTPIN (1450 2125) SIG_NAME GND\g
J 0
(1460 2135);
DISPLAY 0.659574 (1460 2135);
PAINT MONO (1460 2135);
DISPLAY INVISIBLE (1460 2135);
FORCEPROP 2 LAST CDS_LIB logical_power
J 0
(1450 2075);
PAINT MONO (1450 2075);
DISPLAY INVISIBLE (1450 2075);
FORCEPROP 1 LAST HDL_POWER GND
J 1
(1475 2000);
DISPLAY 0.872340 (1475 2000);
PAINT GREEN (1475 2000);
DISPLAY INVISIBLE (1475 2000);
FORCEPROP 1 LAST PATH I54
J 0
(1525 2075);
DISPLAY 0.872340 (1525 2075);
PAINT AQUA (1525 2075);
DISPLAY INVISIBLE (1525 2075);
FORCEADD Q_CAP..1
(1450 2400);
FORCEPROP 1 LAST PART_NUMBER CH647KMEA04
J 0
(1500 2250);
DISPLAY 0.638298 (1500 2250);
DISPLAY INVISIBLE (1500 2250);
FORCEPROP 1 LAST VOLTAGE 4V
J 0
(1500 2400);
DISPLAY 0.638298 (1500 2400);
FORCEPROP 1 LAST TOLERANCE 20%
J 0
(1500 2350);
DISPLAY 0.638298 (1500 2350);
FORCEPROP 1 LAST PACK_TYPE C0805
J 0
(1500 2200);
DISPLAY 0.638298 (1500 2200);
FORCEPROP 1 LAST MATERIAL X6S
J 0
(1500 2300);
DISPLAY 0.638298 (1500 2300);
FORCEPROP 1 LAST VALUE 47UF
J 0
(1500 2450);
DISPLAY 0.638298 (1500 2450);
FORCEPROP 1 LAST $LOCATION C347
J 0
(1500 2500);
DISPLAY 0.638298 (1500 2500);
FORCEPROP 1 LASTPIN (1450 2500) $PN 1
J 0
(1460 2480);
DISPLAY 0.787234 (1460 2480);
FORCEPROP 1 LASTPIN (1450 2300) $PN 2
J 0
(1460 2280);
DISPLAY 0.787234 (1460 2280);
FORCEPROP 2 LAST CDS_LIB pure_quanta
J 0
(1450 2400);
PAINT MONO (1450 2400);
DISPLAY INVISIBLE (1450 2400);
FORCEPROP 1 LAST $LOCATION C347
J 0
(1500 2600);
DISPLAY 1.021277 (1500 2600);
DISPLAY INVISIBLE (1500 2600);
FORCEPROP 2 LAST CDS_LOCATION C347
J 0
(1500 2600);
DISPLAY 1.021277 (1500 2600);
DISPLAY INVISIBLE (1500 2600);
FORCEPROP 2 LAST $SEC 1
J 0
(1500 2600);
DISPLAY 0.680851 (1500 2600);
PAINT MONO (1500 2600);
DISPLAY INVISIBLE (1500 2600);
FORCEPROP 2 LAST CDS_SEC 1
J 0
(1500 2600);
DISPLAY 1.021277 (1500 2600);
DISPLAY INVISIBLE (1500 2600);
FORCEPROP 1 LAST PATH I55
J 0
(1500 2550);
DISPLAY 0.978723 (1500 2550);
PAINT WHITE (1500 2550);
DISPLAY INVISIBLE (1500 2550);
FORCEADD UNIVERSAL_GND..1
(-3075 -1750);
FORCEPROP 3 LASTPIN (-3075 -1700) SIG_NAME GND\g
J 0
(-3065 -1690);
DISPLAY 0.659574 (-3065 -1690);
PAINT MONO (-3065 -1690);
DISPLAY INVISIBLE (-3065 -1690);
FORCEPROP 2 LAST CDS_LIB logical_power
J 0
(-3075 -1750);
PAINT MONO (-3075 -1750);
DISPLAY INVISIBLE (-3075 -1750);
FORCEPROP 1 LAST HDL_POWER GND
J 1
(-3050 -1825);
DISPLAY 0.872340 (-3050 -1825);
PAINT GREEN (-3050 -1825);
DISPLAY INVISIBLE (-3050 -1825);
FORCEPROP 1 LAST PATH I6
J 0
(-3000 -1750);
DISPLAY 0.872340 (-3000 -1750);
PAINT AQUA (-3000 -1750);
DISPLAY INVISIBLE (-3000 -1750);
FORCEADD Q_CAP..1
(-2625 -2375);
FORCEPROP 1 LAST PART_NUMBER CH647KMEA04
J 0
(-2575 -2525);
DISPLAY 0.638298 (-2575 -2525);
DISPLAY INVISIBLE (-2575 -2525);
FORCEPROP 1 LAST VOLTAGE 4V
J 0
(-2575 -2375);
DISPLAY 0.638298 (-2575 -2375);
FORCEPROP 1 LAST TOLERANCE 20%
J 0
(-2575 -2425);
DISPLAY 0.638298 (-2575 -2425);
FORCEPROP 1 LAST PACK_TYPE C0805
J 0
(-2575 -2575);
DISPLAY 0.638298 (-2575 -2575);
FORCEPROP 1 LAST MATERIAL X6S
J 0
(-2575 -2475);
DISPLAY 0.638298 (-2575 -2475);
FORCEPROP 1 LAST VALUE 47UF
J 0
(-2575 -2325);
DISPLAY 0.638298 (-2575 -2325);
FORCEPROP 1 LAST $LOCATION C466
J 0
(-2575 -2275);
DISPLAY 0.978723 (-2575 -2275);
FORCEPROP 1 LASTPIN (-2625 -2275) $PN 1
J 0
(-2615 -2295);
DISPLAY 0.787234 (-2615 -2295);
FORCEPROP 1 LASTPIN (-2625 -2475) $PN 2
J 0
(-2615 -2495);
DISPLAY 0.787234 (-2615 -2495);
FORCEPROP 2 LAST CDS_LIB pure_quanta
J 0
(-2625 -2375);
PAINT MONO (-2625 -2375);
DISPLAY INVISIBLE (-2625 -2375);
FORCEPROP 2 LAST CDS_LOCATION C466
J 0
(-2575 -2175);
DISPLAY 1.021277 (-2575 -2175);
DISPLAY INVISIBLE (-2575 -2175);
FORCEPROP 2 LAST $SEC 1
J 0
(-2575 -2175);
DISPLAY 0.680851 (-2575 -2175);
PAINT MONO (-2575 -2175);
DISPLAY INVISIBLE (-2575 -2175);
FORCEPROP 2 LAST CDS_SEC 1
J 0
(-2575 -2175);
DISPLAY 1.021277 (-2575 -2175);
DISPLAY INVISIBLE (-2575 -2175);
FORCEPROP 1 LAST PATH I7
J 0
(-2575 -2225);
DISPLAY 0.978723 (-2575 -2225);
PAINT WHITE (-2575 -2225);
DISPLAY INVISIBLE (-2575 -2225);
FORCEADD Q_CAP..1
(-2175 -2375);
FORCEPROP 1 LAST PART_NUMBER CH647KMEA04
J 0
(-2125 -2525);
DISPLAY 0.638298 (-2125 -2525);
DISPLAY INVISIBLE (-2125 -2525);
FORCEPROP 1 LAST VOLTAGE 4V
J 0
(-2125 -2375);
DISPLAY 0.638298 (-2125 -2375);
FORCEPROP 1 LAST TOLERANCE 20%
J 0
(-2125 -2425);
DISPLAY 0.638298 (-2125 -2425);
FORCEPROP 1 LAST PACK_TYPE C0805
J 0
(-2125 -2575);
DISPLAY 0.638298 (-2125 -2575);
FORCEPROP 1 LAST MATERIAL X6S
J 0
(-2125 -2475);
DISPLAY 0.638298 (-2125 -2475);
FORCEPROP 1 LAST VALUE 47UF
J 0
(-2125 -2325);
DISPLAY 0.638298 (-2125 -2325);
FORCEPROP 1 LAST $LOCATION C470
J 0
(-2125 -2275);
DISPLAY 0.978723 (-2125 -2275);
FORCEPROP 1 LASTPIN (-2175 -2275) $PN 1
J 0
(-2165 -2295);
DISPLAY 0.787234 (-2165 -2295);
FORCEPROP 1 LASTPIN (-2175 -2475) $PN 2
J 0
(-2165 -2495);
DISPLAY 0.787234 (-2165 -2495);
FORCEPROP 2 LAST CDS_LIB pure_quanta
J 0
(-2175 -2375);
PAINT MONO (-2175 -2375);
DISPLAY INVISIBLE (-2175 -2375);
FORCEPROP 2 LAST CDS_LOCATION C470
J 0
(-2125 -2175);
DISPLAY 1.021277 (-2125 -2175);
DISPLAY INVISIBLE (-2125 -2175);
FORCEPROP 2 LAST $SEC 1
J 0
(-2125 -2175);
DISPLAY 0.680851 (-2125 -2175);
PAINT MONO (-2125 -2175);
DISPLAY INVISIBLE (-2125 -2175);
FORCEPROP 2 LAST CDS_SEC 1
J 0
(-2125 -2175);
DISPLAY 1.021277 (-2125 -2175);
DISPLAY INVISIBLE (-2125 -2175);
FORCEPROP 1 LAST PATH I8
J 0
(-2125 -2225);
DISPLAY 0.978723 (-2125 -2225);
PAINT WHITE (-2125 -2225);
DISPLAY INVISIBLE (-2125 -2225);
FORCEADD Q_CAP..1
(-1725 -2375);
FORCEPROP 1 LAST PART_NUMBER CH647KMEA04
J 0
(-1675 -2525);
DISPLAY 0.638298 (-1675 -2525);
DISPLAY INVISIBLE (-1675 -2525);
FORCEPROP 1 LAST VOLTAGE 4V
J 0
(-1675 -2375);
DISPLAY 0.638298 (-1675 -2375);
FORCEPROP 1 LAST TOLERANCE 20%
J 0
(-1675 -2425);
DISPLAY 0.638298 (-1675 -2425);
FORCEPROP 1 LAST PACK_TYPE C0805
J 0
(-1675 -2575);
DISPLAY 0.638298 (-1675 -2575);
FORCEPROP 1 LAST MATERIAL X6S
J 0
(-1675 -2475);
DISPLAY 0.638298 (-1675 -2475);
FORCEPROP 1 LAST VALUE 47UF
J 0
(-1675 -2325);
DISPLAY 0.638298 (-1675 -2325);
FORCEPROP 1 LAST $LOCATION C473
J 0
(-1675 -2275);
DISPLAY 0.978723 (-1675 -2275);
FORCEPROP 1 LASTPIN (-1725 -2275) $PN 1
J 0
(-1715 -2295);
DISPLAY 0.787234 (-1715 -2295);
FORCEPROP 1 LASTPIN (-1725 -2475) $PN 2
J 0
(-1715 -2495);
DISPLAY 0.787234 (-1715 -2495);
FORCEPROP 2 LAST CDS_LIB pure_quanta
J 0
(-1725 -2375);
PAINT MONO (-1725 -2375);
DISPLAY INVISIBLE (-1725 -2375);
FORCEPROP 2 LAST CDS_LOCATION C473
J 0
(-1675 -2175);
DISPLAY 1.021277 (-1675 -2175);
DISPLAY INVISIBLE (-1675 -2175);
FORCEPROP 2 LAST $SEC 1
J 0
(-1675 -2175);
DISPLAY 0.680851 (-1675 -2175);
PAINT MONO (-1675 -2175);
DISPLAY INVISIBLE (-1675 -2175);
FORCEPROP 2 LAST CDS_SEC 1
J 0
(-1675 -2175);
DISPLAY 1.021277 (-1675 -2175);
DISPLAY INVISIBLE (-1675 -2175);
FORCEPROP 1 LAST PATH I9
J 0
(-1675 -2225);
DISPLAY 0.978723 (-1675 -2225);
PAINT WHITE (-1675 -2225);
DISPLAY INVISIBLE (-1675 -2225);
FORCEADD QUANTA_TITLE_BLOCK_C..1
(4650 -3400);
FORCEPROP 0 LAST CDS_CON_LAST_MODIFIED Fri Aug 25 14:00:59 2023
J 0
(2765 -3385);
PAINT MONO (2765 -3385);
DISPLAY INVISIBLE (2765 -3385);
FORCEPROP 2 LAST CUSTOM_TXT_CDS <XR_PAGE_TITLE>
J 0
(-3240 1850);
DISPLAY 0.638298 (-3240 1850);
PAINT PINK (-3240 1850);
DISPLAY INVISIBLE (-3240 1850);
FORCEPROP 2 LAST CUSTOM_TXT_CDS <Q_NUMBER>
J 0
(3247 -3297);
DISPLAY 1.212766 (3247 -3297);
FORCEPROP 2 LAST CUSTOM_TXT_CDS <CON_LAST_MODIFIED>
J 0
(2825 -3400);
DISPLAY 0.978723 (2825 -3400);
FORCEPROP 1 LAST CUSTOM_TXT_CDS <NAME_2>
J 0
(1475 -3350);
FORCEPROP 1 LAST CUSTOM_TXT_CDS <NAME_1>
J 0
(1475 -3225);
FORCEPROP 1 LAST CUSTOM_TXT_CDS <Q_PROJ>
J 0
(2268 -3298);
DISPLAY 1.212766 (2268 -3298);
FORCEPROP 1 LAST CUSTOM_TXT_CDS <Q_REV>
J 0
(4466 -3297);
DISPLAY 1.212766 (4466 -3297);
FORCEPROP 1 LAST CUSTOM_TXT_CDS <CON_PAGE_NUM> OF <CON_TOTAL_PAGES>
J 0
(4204 -3382);
DISPLAY 0.978723 (4204 -3382);
FORCEPROP 1 LAST Q_TITLE SPR CPU1 BOTTOM DECOUPLING CAPS CONTI.
J 0
(-4691 -3374);
DISPLAY 1.957447 (-4691 -3374);
PAINT GREEN (-4691 -3374);
FORCEPROP 1 LAST Q_DEPT 
J 1
(887 -3351);
DISPLAY 1.957447 (887 -3351);
PAINT GREEN (887 -3351);
FORCEPROP 1 LAST COMMENT_BODY TRUE
J 0
(4662 -3413);
DISPLAY 0.978723 (4662 -3413);
PAINT GREEN (4662 -3413);
DISPLAY INVISIBLE (4662 -3413);
FORCEPROP 2 LAST CDS_XR_PAGE_TITLE CR-79 : @S9S_MB_2U_LIB.S9S_MB_2U(SCH_1):PAGE79
J 0
(-3240 1850);
DISPLAY 0.638298 (-3240 1850);
PAINT PINK (-3240 1850);
DISPLAY INVISIBLE (-3240 1850);
FORCEPROP 2 LAST CDS_LIB pure_quanta
J 0
(4650 -3400);
PAINT MONO (4650 -3400);
DISPLAY INVISIBLE (4650 -3400);
FORCEPROP 1 LAST CDS_LMAN_SYM_OUTLINE -9475,6775,100,-125
J 0
(4650 -3400);
DISPLAY 0.468085 (4650 -3400);
PAINT GREEN (4650 -3400);
DISPLAY INVISIBLE (4650 -3400);
FORCEPROP 2 LAST PAGE_BORDER TRUE
J 0
(-3240 1850);
DISPLAY 0.638298 (-3240 1850);
PAINT PINK (-3240 1850);
DISPLAY INVISIBLE (-3240 1850);
WIRE 16 -1 (-4425 -2200)(-4425 -2150);
WIRE 16 -1 (-3975 -2200)(-4425 -2200);
WIRE 16 -1 (-4425 -2200)(-4425 -2275);
WIRE 16 -1 (-4425 -1225)(-4425 -1175);
WIRE 16 -1 (-3975 -1225)(-4425 -1225);
WIRE 16 -1 (-4425 -1300)(-4425 -1225);
WIRE 16 -1 (-4425 -225)(-4425 -175);
WIRE 16 -1 (-3975 -225)(-4425 -225);
WIRE 16 -1 (-4425 -225)(-4425 -300);
WIRE 16 -1 (-4400 1650)(-4400 1700);
WIRE 16 -1 (-3950 1650)(-4400 1650);
WIRE 16 -1 (-4400 1650)(-4400 1575);
WIRE 16 -1 (-4400 2575)(-4400 2625);
WIRE 16 -1 (-3950 2575)(-4400 2575);
WIRE 16 -1 (-4400 2575)(-4400 2500);
WIRE 16 -1 (-1175 1625)(-1175 1675);
WIRE 16 -1 (-725 1625)(-1175 1625);
WIRE 16 -1 (-1175 1625)(-1175 1550);
WIRE 16 -1 (-3075 -1700)(-3075 -1625);
WIRE 16 -1 (-3050 1200)(-3050 1250);
WIRE 16 -1 (525 -2675)(525 -2600);
WIRE 16 -1 (-325 1150)(-325 1225);
WIRE 16 -1 (1450 2125)(1450 2175);
WIRE 16 -1 (-2175 -700)(-2175 -625);
WIRE 16 -1 (-3975 -300)(-3975 -225);
WIRE 16 -1 (-3525 -225)(-3975 -225);
WIRE 16 -1 (-3525 -300)(-3525 -225);
WIRE 16 -1 (-3075 -225)(-3525 -225);
WIRE 16 -1 (-3075 -300)(-3075 -225);
WIRE 16 -1 (-2625 -225)(-3075 -225);
WIRE 16 -1 (-2625 -225)(-2625 -300);
WIRE 16 -1 (-2175 -225)(-2625 -225);
WIRE 16 -1 (-2175 -225)(-2175 -300);
WIRE 16 -1 (-4425 -2600)(-4425 -2475);
WIRE 16 -1 (-3975 -2600)(-4425 -2600);
WIRE 16 -1 (-3975 -2600)(-3975 -2475);
WIRE 16 -1 (-3525 -2600)(-3975 -2600);
WIRE 16 -1 (-3525 -2600)(-3525 -2475);
WIRE 16 -1 (-3075 -2600)(-3525 -2600);
WIRE 16 -1 (-3075 -2600)(-3075 -2475);
WIRE 16 -1 (-2625 -2600)(-3075 -2600);
WIRE 16 -1 (-2625 -2600)(-2625 -2475);
WIRE 16 -1 (-2175 -2600)(-2625 -2600);
WIRE 16 -1 (-2175 -2600)(-2175 -2475);
WIRE 16 -1 (-1725 -2600)(-2175 -2600);
WIRE 16 -1 (-1725 -2600)(-1725 -2475);
WIRE 16 -1 (-1275 -2600)(-1725 -2600);
WIRE 16 -1 (-1275 -2600)(-1275 -2475);
WIRE 16 -1 (-825 -2600)(-1275 -2600);
WIRE 16 -1 (-825 -2600)(-825 -2475);
WIRE 16 -1 (-375 -2600)(-825 -2600);
WIRE 16 -1 (-375 -2600)(-375 -2475);
WIRE 16 -1 (75 -2600)(-375 -2600);
WIRE 16 -1 (75 -2600)(75 -2475);
WIRE 16 -1 (525 -2600)(75 -2600);
WIRE 16 -1 (525 -2600)(525 -2475);
WIRE 16 -1 (-4425 -1625)(-4425 -1500);
WIRE 16 -1 (-3075 -1625)(-3075 -1500);
WIRE 16 -1 (-3975 -1625)(-4425 -1625);
WIRE 16 -1 (-3975 -1625)(-3975 -1500);
WIRE 16 -1 (-3525 -1625)(-3975 -1625);
WIRE 16 -1 (-3075 -1625)(-3525 -1625);
WIRE 16 -1 (-3525 -1625)(-3525 -1500);
WIRE 16 -1 (-4400 2175)(-4400 2300);
WIRE 16 -1 (-3950 2175)(-4400 2175);
WIRE 16 -1 (-3950 2175)(-3950 2300);
WIRE 16 -1 (-3500 2175)(-3950 2175);
WIRE 16 -1 (-3500 2175)(-3500 2300);
WIRE 16 -1 (-3050 2175)(-3500 2175);
WIRE 16 -1 (-3050 2175)(-3050 2300);
WIRE 16 -1 (-2600 2175)(-3050 2175);
WIRE 16 -1 (-2600 2175)(-2600 2300);
WIRE 16 -1 (-2150 2175)(-2600 2175);
WIRE 16 -1 (-2150 2175)(-2150 2300);
WIRE 16 -1 (-1700 2175)(-2150 2175);
WIRE 16 -1 (-1700 2175)(-1700 2300);
WIRE 16 -1 (-1250 2175)(-1700 2175);
WIRE 16 -1 (-1250 2175)(-1250 2300);
WIRE 16 -1 (-800 2175)(-1250 2175);
WIRE 16 -1 (-800 2175)(-800 2300);
WIRE 16 -1 (-350 2175)(-800 2175);
WIRE 16 -1 (-350 2175)(-350 2300);
WIRE 16 -1 (100 2175)(-350 2175);
WIRE 16 -1 (100 2175)(100 2300);
WIRE 16 -1 (550 2175)(100 2175);
WIRE 16 -1 (550 2175)(550 2300);
WIRE 16 -1 (1000 2175)(550 2175);
WIRE 16 -1 (1000 2175)(1000 2300);
WIRE 16 -1 (1450 2175)(1000 2175);
WIRE 16 -1 (1450 2300)(1450 2175);
WIRE 16 -1 (-3950 2500)(-3950 2575);
WIRE 16 -1 (-3500 2575)(-3950 2575);
WIRE 16 -1 (-3500 2575)(-3500 2500);
WIRE 16 -1 (-3050 2575)(-3500 2575);
WIRE 16 -1 (-3050 2500)(-3050 2575);
WIRE 16 -1 (-2600 2500)(-2600 2575);
WIRE 16 -1 (-2600 2575)(-3050 2575);
WIRE 16 -1 (-2150 2575)(-2600 2575);
WIRE 16 -1 (-2150 2575)(-2150 2500);
WIRE 16 -1 (-1700 2575)(-2150 2575);
WIRE 16 -1 (-1700 2500)(-1700 2575);
WIRE 16 -1 (-1250 2575)(-1700 2575);
WIRE 16 -1 (-1250 2500)(-1250 2575);
WIRE 16 -1 (-800 2575)(-1250 2575);
WIRE 16 -1 (-800 2500)(-800 2575);
WIRE 16 -1 (-350 2575)(-800 2575);
WIRE 16 -1 (-350 2575)(-350 2500);
WIRE 16 -1 (100 2575)(-350 2575);
WIRE 16 -1 (100 2575)(100 2500);
WIRE 16 -1 (550 2575)(100 2575);
WIRE 16 -1 (550 2500)(550 2575);
WIRE 16 -1 (1000 2575)(1000 2500);
WIRE 16 -1 (1000 2575)(550 2575);
WIRE 16 -1 (1450 2575)(1000 2575);
WIRE 16 -1 (1450 2500)(1450 2575);
WIRE 16 -1 (-1175 1225)(-1175 1350);
WIRE 16 -1 (-725 1225)(-1175 1225);
WIRE 16 -1 (-725 1225)(-725 1350);
WIRE 16 -1 (-325 1225)(-725 1225);
WIRE 16 -1 (-325 1350)(-325 1225);
WIRE 16 -1 (-725 1550)(-725 1625);
WIRE 16 -1 (-325 1625)(-725 1625);
WIRE 16 -1 (-325 1550)(-325 1625);
WIRE 16 -1 (-3975 -2275)(-3975 -2200);
WIRE 16 -1 (-3525 -2200)(-3975 -2200);
WIRE 16 -1 (-3525 -2200)(-3525 -2275);
WIRE 16 -1 (-3075 -2200)(-3525 -2200);
WIRE 16 -1 (-3075 -2275)(-3075 -2200);
WIRE 16 -1 (-2625 -2200)(-3075 -2200);
WIRE 16 -1 (-2625 -2275)(-2625 -2200);
WIRE 16 -1 (-2175 -2200)(-2625 -2200);
WIRE 16 -1 (-2175 -2200)(-2175 -2275);
WIRE 16 -1 (-1725 -2200)(-2175 -2200);
WIRE 16 -1 (-1725 -2275)(-1725 -2200);
WIRE 16 -1 (-1275 -2200)(-1725 -2200);
WIRE 16 -1 (-1275 -2200)(-1275 -2275);
WIRE 16 -1 (-825 -2200)(-1275 -2200);
WIRE 16 -1 (-825 -2275)(-825 -2200);
WIRE 16 -1 (-375 -2200)(-825 -2200);
WIRE 16 -1 (-375 -2275)(-375 -2200);
WIRE 16 -1 (75 -2200)(-375 -2200);
WIRE 16 -1 (75 -2200)(75 -2275);
WIRE 16 -1 (525 -2200)(75 -2200);
WIRE 16 -1 (525 -2200)(525 -2275);
WIRE 16 -1 (-4425 -625)(-4425 -500);
WIRE 16 -1 (-3975 -625)(-4425 -625);
WIRE 16 -1 (-3975 -625)(-3975 -500);
WIRE 16 -1 (-3525 -625)(-3975 -625);
WIRE 16 -1 (-3525 -625)(-3525 -500);
WIRE 16 -1 (-3075 -625)(-3525 -625);
WIRE 16 -1 (-3075 -625)(-3075 -500);
WIRE 16 -1 (-2625 -625)(-3075 -625);
WIRE 16 -1 (-2625 -625)(-2625 -500);
WIRE 16 -1 (-2175 -625)(-2625 -625);
WIRE 16 -1 (-2175 -625)(-2175 -500);
WIRE 16 -1 (-3950 1575)(-3950 1650);
WIRE 16 -1 (-3500 1650)(-3950 1650);
WIRE 16 -1 (-3500 1650)(-3500 1575);
WIRE 16 -1 (-3050 1650)(-3500 1650);
WIRE 16 -1 (-3050 1575)(-3050 1650);
WIRE 16 -1 (-3975 -1300)(-3975 -1225);
WIRE 16 -1 (-3525 -1225)(-3975 -1225);
WIRE 16 -1 (-3525 -1300)(-3525 -1225);
WIRE 16 -1 (-3075 -1225)(-3525 -1225);
WIRE 16 -1 (-3075 -1225)(-3075 -1300);
WIRE 16 -1 (-4400 1250)(-4400 1375);
WIRE 16 -1 (-3950 1250)(-4400 1250);
WIRE 16 -1 (-3950 1250)(-3950 1375);
WIRE 16 -1 (-3500 1250)(-3950 1250);
WIRE 16 -1 (-3500 1250)(-3500 1375);
WIRE 16 -1 (-3050 1250)(-3500 1250);
WIRE 16 -1 (-3050 1375)(-3050 1250);
DOT 1 (1450 2175);
DOT 1 (1000 2575);
DOT 1 (1000 2175);
DOT 1 (550 2575);
DOT 1 (550 2175);
DOT 1 (100 2575);
DOT 1 (100 2175);
DOT 1 (-350 2575);
DOT 1 (-350 2175);
DOT 1 (-325 1225);
DOT 1 (-800 2575);
DOT 1 (-800 2175);
DOT 1 (-725 1625);
DOT 1 (-1250 2575);
DOT 1 (-1250 2175);
DOT 1 (-1175 1625);
DOT 1 (-725 1225);
DOT 1 (75 -2200);
DOT 1 (-375 -2200);
DOT 1 (525 -2600);
DOT 1 (75 -2600);
DOT 1 (-375 -2600);
DOT 1 (-825 -2200);
DOT 1 (-1275 -2200);
DOT 1 (-825 -2600);
DOT 1 (-1275 -2600);
DOT 1 (-1700 2575);
DOT 1 (-1700 2175);
DOT 1 (-2150 2575);
DOT 1 (-2150 2175);
DOT 1 (-2600 2575);
DOT 1 (-2600 2175);
DOT 1 (-3050 2575);
DOT 1 (-3050 2175);
DOT 1 (-3050 1250);
DOT 1 (-2175 -625);
DOT 1 (-2625 -225);
DOT 1 (-3075 -225);
DOT 1 (-2625 -625);
DOT 1 (-3075 -625);
DOT 1 (-3500 2575);
DOT 1 (-3500 2175);
DOT 1 (-3950 2575);
DOT 1 (-3950 2175);
DOT 1 (-3500 1650);
DOT 1 (-3950 1650);
DOT 1 (-4400 2575);
DOT 1 (-4400 1650);
DOT 1 (-3500 1250);
DOT 1 (-3950 1250);
DOT 1 (-3525 -225);
DOT 1 (-3975 -225);
DOT 1 (-4425 -225);
DOT 1 (-3525 -625);
DOT 1 (-3525 -1225);
DOT 1 (-3975 -1225);
DOT 1 (-3975 -625);
DOT 1 (-4425 -1225);
DOT 1 (-1725 -2200);
DOT 1 (-2175 -2200);
DOT 1 (-1725 -2600);
DOT 1 (-2175 -2600);
DOT 1 (-2625 -2200);
DOT 1 (-3075 -1625);
DOT 1 (-3075 -2200);
DOT 1 (-2625 -2600);
DOT 1 (-3075 -2600);
DOT 1 (-3525 -1625);
DOT 1 (-3525 -2200);
DOT 1 (-3975 -2200);
DOT 1 (-3975 -1625);
DOT 1 (-4425 -2200);
DOT 1 (-3525 -2600);
DOT 1 (-3975 -2600);
FORCENOTE
PVCCFA_EHV: 6 MLCC CAPS PLACED AT CPU(UP>
(-3525 -175) 0;
DISPLAY LEFT (-3525 -175);
DISPLAY 0.808511 (-3525 -175);
PAINT SKYBLUE (-3525 -175);
FORCENOTE
PVCCFA_EHV: 6 0805 100UF MLCC CAPS PLACED AT CPU(LEFT>
(-3511 -2057) 0;
DISPLAY LEFT (-3511 -2057);
DISPLAY 0.808511 (-3511 -2057);
PAINT SKYBLUE (-3511 -2057);
FORCENOTE
PVCCFA_EHV: 6 0805 100UF MLCC CAPS PLACED AT CPU(RIGHT>
(-3511 -2132) 0;
DISPLAY LEFT (-3511 -2132);
DISPLAY 0.808511 (-3511 -2132);
PAINT SKYBLUE (-3511 -2132);
FORCENOTE
PVCCIN: 14 0805 100UF MLCC CAPS PLACED AT CPU(DOWN>
(-3500 2625) 0;
DISPLAY LEFT (-3500 2625);
DISPLAY 0.808511 (-3500 2625);
PAINT SKYBLUE (-3500 2625);
FORCENOTE
PVCCD_HV: 4 MLCC CAPS PLACED AT CPU(UP>
(-3500 1700) 0;
DISPLAY LEFT (-3500 1700);
DISPLAY 0.808511 (-3500 1700);
PAINT SKYBLUE (-3500 1700);
FORCENOTE
PVCCINFAON: 4 MLCC CAPS PLACED AT CPU(UP>
(-3525 -1175) 0;
DISPLAY LEFT (-3525 -1175);
DISPLAY 0.808511 (-3525 -1175);
PAINT SKYBLUE (-3525 -1175);
QUIT
